G04 ================== begin FILE IDENTIFICATION RECORD ==================*
G04 Layout Name:  15669-1.brd*
G04 Film Name:    DP_REF_L6*
G04 File Format:  Gerber RS274X*
G04 File Origin:  Cadence Allegro 16.5-S056*
G04 Origin Date:  Wed Nov 16 04:09:22 2016*
G04 *
G04 Layer:  BOARD GEOMETRY/DP_REF_L6_TBL*
G04 Layer:  BOARD GEOMETRY/DP_REF_L6_L6*
G04 Layer:  BOARD GEOMETRY/PANEL_OUTLINE*
G04 *
G04 Offset:    (0.00 0.00)*
G04 Mirror:    No*
G04 Mode:      Positive*
G04 Rotation:  0*
G04 FullContactRelief:  No*
G04 UndefLineWidth:     6.00*
G04 ================== end FILE IDENTIFICATION RECORD ====================*
%FSLAX35Y35*MOIN*%
%IR0*IPPOS*OFA0.00000B0.00000*MIA0B0*SFA1.00000B1.00000*%
%ADD10C,.02*%
%ADD11C,.006*%
%ADD12C,.0065*%
G75*
%LPD*%
G75*
G54D10*
G01X1178253Y1853826D02*
X1965753D01*
G01X1178253Y1957776D02*
Y1853826D01*
G01Y1923126D02*
X1965753D01*
G01X1178253Y1888476D02*
X1965753D01*
G01X1178253Y1957776D02*
X1965753D01*
G01X1353253D02*
Y1853826D01*
G01X1650753Y1957776D02*
Y1853826D01*
G01X1755753Y1957776D02*
Y1853826D01*
G01X1965753Y1957776D02*
Y1853826D01*
G54D11*
G01X-84302Y-32800D02*
Y-50300D01*
G01X-89324Y-32800D02*
X-79280D01*
G01X-70514Y-50300D02*
Y-32800D01*
G01Y-41258D02*
X-69422Y-39800D01*
X-68330Y-38925D01*
X-66584Y-38634D01*
X-65274Y-38925D01*
X-63745Y-40092D01*
X-63090Y-41842D01*
Y-50300D01*
G01X-49302Y-38634D02*
Y-50300D01*
G01Y-33967D02*
X-49739Y-33675D01*
Y-33092D01*
X-49302Y-32800D01*
X-48865Y-33092D01*
Y-33675D01*
X-49302Y-33967D01*
G01X-35077Y-48259D02*
X-33985Y-49425D01*
X-32457Y-50300D01*
X-31147D01*
X-29837Y-49717D01*
X-28964Y-48842D01*
X-28527Y-47676D01*
X-28745Y-45925D01*
X-29619Y-45050D01*
X-33549Y-43300D01*
X-34422Y-41258D01*
X-33985Y-39800D01*
X-33112Y-38925D01*
X-31802Y-38634D01*
X-30492Y-38925D01*
X-29182Y-39800D01*
G01X141Y-54675D02*
X1670Y-55842D01*
X3416Y-56133D01*
X4944Y-55842D01*
X6255Y-54384D01*
X7128Y-52342D01*
Y-38634D01*
G01Y-40967D02*
X6255Y-39800D01*
X4944Y-38925D01*
X3416Y-38634D01*
X1670Y-39217D01*
X578Y-40383D01*
X-296Y-42425D01*
X-732Y-44467D01*
X-514Y-46217D01*
X360Y-48259D01*
X1670Y-49717D01*
X3416Y-50300D01*
X4726Y-50008D01*
X6255Y-48842D01*
X7128Y-47676D01*
G01X17423Y-42425D02*
X24410D01*
X23755Y-40383D01*
X22663Y-39217D01*
X21135Y-38634D01*
X19606Y-38925D01*
X18296Y-39800D01*
X17423Y-41842D01*
X16986Y-43592D01*
Y-45342D01*
X17423Y-47092D01*
X18515Y-48842D01*
X19825Y-50008D01*
X21353Y-50300D01*
X22881Y-49717D01*
X24410Y-47967D01*
G01X35141Y-50300D02*
Y-38634D01*
G01Y-40967D02*
X36233Y-39800D01*
X37325Y-38925D01*
X38853Y-38634D01*
X39944Y-38925D01*
X41255Y-39800D01*
G01X51768Y-50300D02*
Y-32800D01*
G01Y-41550D02*
X52860Y-39800D01*
X54170Y-38925D01*
X55480Y-38634D01*
X57444Y-39217D01*
X58755Y-40383D01*
X59628Y-42425D01*
Y-44758D01*
X59191Y-47092D01*
X58318Y-48842D01*
X56790Y-50008D01*
X55480Y-50300D01*
X54170Y-50008D01*
X52860Y-49134D01*
X51768Y-47676D01*
G01X69923Y-42425D02*
X76910D01*
X76255Y-40383D01*
X75163Y-39217D01*
X73635Y-38634D01*
X72106Y-38925D01*
X70796Y-39800D01*
X69923Y-41842D01*
X69486Y-43592D01*
Y-45342D01*
X69923Y-47092D01*
X71015Y-48842D01*
X72325Y-50008D01*
X73853Y-50300D01*
X75381Y-49717D01*
X76910Y-47967D01*
G01X87641Y-50300D02*
Y-38634D01*
G01Y-40967D02*
X88733Y-39800D01*
X89825Y-38925D01*
X91353Y-38634D01*
X92444Y-38925D01*
X93755Y-39800D01*
G01X125698Y-38634D02*
Y-50300D01*
G01Y-33967D02*
X125261Y-33675D01*
Y-33092D01*
X125698Y-32800D01*
X126135Y-33092D01*
Y-33675D01*
X125698Y-33967D01*
G01X139923Y-48259D02*
X141015Y-49425D01*
X142543Y-50300D01*
X143853D01*
X145163Y-49717D01*
X146036Y-48842D01*
X146473Y-47676D01*
X146255Y-45925D01*
X145381Y-45050D01*
X141451Y-43300D01*
X140578Y-41258D01*
X141015Y-39800D01*
X141888Y-38925D01*
X143198Y-38634D01*
X144508Y-38925D01*
X145818Y-39800D01*
G01X174704Y-54675D02*
X176233Y-55842D01*
X177543Y-56133D01*
X179290Y-55550D01*
X180600Y-54092D01*
X181255Y-51466D01*
Y-38634D01*
G01Y-33967D02*
X180818Y-33675D01*
Y-33092D01*
X181255Y-32800D01*
X181691Y-33092D01*
Y-33675D01*
X181255Y-33967D01*
G01X191986Y-38634D02*
Y-46800D01*
X192860Y-48842D01*
X194170Y-50008D01*
X195698Y-50300D01*
X197226Y-50008D01*
X198536Y-48842D01*
X199410Y-46800D01*
G01Y-50300D02*
Y-38634D01*
G01X209923Y-48259D02*
X211015Y-49425D01*
X212543Y-50300D01*
X213853D01*
X215163Y-49717D01*
X216036Y-48842D01*
X216473Y-47676D01*
X216255Y-45925D01*
X215381Y-45050D01*
X211451Y-43300D01*
X210578Y-41258D01*
X211015Y-39800D01*
X211888Y-38925D01*
X213198Y-38634D01*
X214508Y-38925D01*
X215818Y-39800D01*
G01X230698Y-32800D02*
Y-50300D01*
G01X227641Y-38634D02*
X233755D01*
G01X264388Y-50300D02*
Y-35425D01*
X264825Y-33967D01*
X265698Y-33092D01*
X267008Y-32800D01*
X268318Y-33383D01*
X268973Y-34842D01*
G01X266353Y-39800D02*
X261986D01*
G01X283198Y-50300D02*
X281888Y-50008D01*
X280578Y-48842D01*
X279704Y-46800D01*
X279268Y-44467D01*
X279704Y-42133D01*
X280578Y-40092D01*
X281888Y-38925D01*
X283198Y-38634D01*
X284508Y-38925D01*
X285818Y-40092D01*
X286691Y-42133D01*
X286910Y-44467D01*
X286691Y-46800D01*
X285818Y-48842D01*
X284508Y-50008D01*
X283198Y-50300D01*
G01X297641D02*
Y-38634D01*
G01Y-40967D02*
X298733Y-39800D01*
X299825Y-38925D01*
X301353Y-38634D01*
X302444Y-38925D01*
X303755Y-39800D01*
G01X331113Y-55550D02*
X332423Y-56133D01*
X334170Y-55550D01*
X335261Y-54384D01*
X336135Y-52925D01*
X337444Y-48259D01*
X340283Y-38634D01*
G01X333296D02*
X337444Y-48259D01*
G01X353198Y-50300D02*
X351888Y-50008D01*
X350578Y-48842D01*
X349704Y-46800D01*
X349268Y-44467D01*
X349704Y-42133D01*
X350578Y-40092D01*
X351888Y-38925D01*
X353198Y-38634D01*
X354508Y-38925D01*
X355818Y-40092D01*
X356691Y-42133D01*
X356910Y-44467D01*
X356691Y-46800D01*
X355818Y-48842D01*
X354508Y-50008D01*
X353198Y-50300D01*
G01X366986Y-38634D02*
Y-46800D01*
X367860Y-48842D01*
X369170Y-50008D01*
X370698Y-50300D01*
X372226Y-50008D01*
X373536Y-48842D01*
X374410Y-46800D01*
G01Y-50300D02*
Y-38634D01*
G01X385141Y-50300D02*
Y-38634D01*
G01Y-40967D02*
X386233Y-39800D01*
X387325Y-38925D01*
X388853Y-38634D01*
X389944Y-38925D01*
X391255Y-39800D01*
G01X420141Y-50300D02*
Y-38634D01*
G01Y-40967D02*
X421233Y-39800D01*
X422325Y-38925D01*
X423853Y-38634D01*
X424944Y-38925D01*
X426255Y-39800D01*
G01X437423Y-42425D02*
X444410D01*
X443755Y-40383D01*
X442663Y-39217D01*
X441135Y-38634D01*
X439606Y-38925D01*
X438296Y-39800D01*
X437423Y-41842D01*
X436986Y-43592D01*
Y-45342D01*
X437423Y-47092D01*
X438515Y-48842D01*
X439825Y-50008D01*
X441353Y-50300D01*
X442881Y-49717D01*
X444410Y-47967D01*
G01X456888Y-50300D02*
Y-35425D01*
X457325Y-33967D01*
X458198Y-33092D01*
X459508Y-32800D01*
X460818Y-33383D01*
X461473Y-34842D01*
G01X458853Y-39800D02*
X454486D01*
G01X472423Y-42425D02*
X479410D01*
X478755Y-40383D01*
X477663Y-39217D01*
X476135Y-38634D01*
X474606Y-38925D01*
X473296Y-39800D01*
X472423Y-41842D01*
X471986Y-43592D01*
Y-45342D01*
X472423Y-47092D01*
X473515Y-48842D01*
X474825Y-50008D01*
X476353Y-50300D01*
X477881Y-49717D01*
X479410Y-47967D01*
G01X490141Y-50300D02*
Y-38634D01*
G01Y-40967D02*
X491233Y-39800D01*
X492325Y-38925D01*
X493853Y-38634D01*
X494944Y-38925D01*
X496255Y-39800D01*
G01X507423Y-42425D02*
X514410D01*
X513755Y-40383D01*
X512663Y-39217D01*
X511135Y-38634D01*
X509606Y-38925D01*
X508296Y-39800D01*
X507423Y-41842D01*
X506986Y-43592D01*
Y-45342D01*
X507423Y-47092D01*
X508515Y-48842D01*
X509825Y-50008D01*
X511353Y-50300D01*
X512881Y-49717D01*
X514410Y-47967D01*
G01X524486Y-50300D02*
Y-38634D01*
G01Y-41550D02*
X525360Y-40092D01*
X526670Y-38925D01*
X528416Y-38634D01*
X529944Y-38925D01*
X531255Y-40092D01*
X531910Y-42133D01*
Y-50300D01*
G01X549191Y-40092D02*
X547663Y-38925D01*
X546353Y-38634D01*
X544606Y-39217D01*
X543296Y-40383D01*
X542423Y-42425D01*
X542204Y-44467D01*
X542423Y-46509D01*
X543296Y-48259D01*
X544606Y-49717D01*
X546353Y-50300D01*
X547881Y-49717D01*
X549191Y-48550D01*
G01X559923Y-42425D02*
X566910D01*
X566255Y-40383D01*
X565163Y-39217D01*
X563635Y-38634D01*
X562106Y-38925D01*
X560796Y-39800D01*
X559923Y-41842D01*
X559486Y-43592D01*
Y-45342D01*
X559923Y-47092D01*
X561015Y-48842D01*
X562325Y-50008D01*
X563853Y-50300D01*
X565381Y-49717D01*
X566910Y-47967D01*
G01X598198Y-32800D02*
Y-50300D01*
G01X595141Y-38634D02*
X601255D01*
G01X615698Y-50300D02*
X614388Y-50008D01*
X613078Y-48842D01*
X612204Y-46800D01*
X611768Y-44467D01*
X612204Y-42133D01*
X613078Y-40092D01*
X614388Y-38925D01*
X615698Y-38634D01*
X617008Y-38925D01*
X618318Y-40092D01*
X619191Y-42133D01*
X619410Y-44467D01*
X619191Y-46800D01*
X618318Y-48842D01*
X617008Y-50008D01*
X615698Y-50300D01*
G01X649388D02*
Y-35425D01*
X649825Y-33967D01*
X650698Y-33092D01*
X652008Y-32800D01*
X653318Y-33383D01*
X653973Y-34842D01*
G01X651353Y-39800D02*
X646986D01*
G01X668198Y-38634D02*
Y-50300D01*
G01Y-33967D02*
X667761Y-33675D01*
Y-33092D01*
X668198Y-32800D01*
X668635Y-33092D01*
Y-33675D01*
X668198Y-33967D01*
G01X681986Y-50300D02*
Y-38634D01*
G01Y-41550D02*
X682860Y-40092D01*
X684170Y-38925D01*
X685916Y-38634D01*
X687444Y-38925D01*
X688755Y-40092D01*
X689410Y-42133D01*
Y-50300D01*
G01X707128Y-32800D02*
Y-50300D01*
G01Y-47676D02*
X706255Y-49134D01*
X704944Y-50008D01*
X703416Y-50300D01*
X701670Y-49717D01*
X700360Y-48259D01*
X699486Y-46509D01*
X699268Y-44467D01*
X699486Y-42425D01*
X700360Y-40675D01*
X701670Y-39217D01*
X703416Y-38634D01*
X704944Y-38925D01*
X706036Y-39509D01*
X707128Y-40675D01*
G01X738198Y-32800D02*
Y-50300D01*
G01X735141Y-38634D02*
X741255D01*
G01X751986Y-50300D02*
Y-32800D01*
G01Y-41258D02*
X753078Y-39800D01*
X754170Y-38925D01*
X755916Y-38634D01*
X757226Y-38925D01*
X758755Y-40092D01*
X759410Y-41842D01*
Y-50300D01*
G01X769923Y-42425D02*
X776910D01*
X776255Y-40383D01*
X775163Y-39217D01*
X773635Y-38634D01*
X772106Y-38925D01*
X770796Y-39800D01*
X769923Y-41842D01*
X769486Y-43592D01*
Y-45342D01*
X769923Y-47092D01*
X771015Y-48842D01*
X772325Y-50008D01*
X773853Y-50300D01*
X775381Y-49717D01*
X776910Y-47967D01*
G01X803395Y-50300D02*
Y-32800D01*
X807761D01*
X809508Y-33675D01*
X810818Y-34842D01*
X811910Y-36591D01*
X812783Y-38634D01*
X813001Y-41550D01*
X812783Y-44467D01*
X811910Y-46509D01*
X810818Y-48259D01*
X809508Y-49425D01*
X807761Y-50300D01*
X803395D01*
G01X821331D02*
Y-32800D01*
X826571D01*
X828318Y-33675D01*
X829628Y-35717D01*
X830065Y-38050D01*
X829628Y-40383D01*
X828536Y-42133D01*
X826571Y-43009D01*
X821331D01*
G01X860698Y-38634D02*
Y-50300D01*
G01Y-33967D02*
X860261Y-33675D01*
Y-33092D01*
X860698Y-32800D01*
X861135Y-33092D01*
Y-33675D01*
X860698Y-33967D01*
G01X871648Y-50300D02*
Y-38634D01*
G01Y-41842D02*
X872303Y-40383D01*
X873395Y-39217D01*
X874923Y-38634D01*
X876451Y-39217D01*
X877543Y-40383D01*
X878198Y-41842D01*
Y-50300D01*
G01Y-41842D02*
X878853Y-40383D01*
X879944Y-39217D01*
X881473Y-38634D01*
X883001Y-39217D01*
X884093Y-40383D01*
X884748Y-42133D01*
Y-50300D01*
G01X891768Y-56133D02*
Y-38634D01*
G01Y-41258D02*
X892860Y-39800D01*
X893951Y-38925D01*
X895698Y-38634D01*
X897226Y-38925D01*
X898755Y-40383D01*
X899410Y-42425D01*
X899628Y-44467D01*
X899410Y-46509D01*
X898755Y-48550D01*
X897444Y-49717D01*
X895698Y-50300D01*
X894170Y-50008D01*
X892641Y-49134D01*
X891768Y-47967D01*
G01X909923Y-42425D02*
X916910D01*
X916255Y-40383D01*
X915163Y-39217D01*
X913635Y-38634D01*
X912106Y-38925D01*
X910796Y-39800D01*
X909923Y-41842D01*
X909486Y-43592D01*
Y-45342D01*
X909923Y-47092D01*
X911015Y-48842D01*
X912325Y-50008D01*
X913853Y-50300D01*
X915381Y-49717D01*
X916910Y-47967D01*
G01X934628Y-32800D02*
Y-50300D01*
G01Y-47676D02*
X933755Y-49134D01*
X932444Y-50008D01*
X930916Y-50300D01*
X929170Y-49717D01*
X927860Y-48259D01*
X926986Y-46509D01*
X926768Y-44467D01*
X926986Y-42425D01*
X927860Y-40675D01*
X929170Y-39217D01*
X930916Y-38634D01*
X932444Y-38925D01*
X933536Y-39509D01*
X934628Y-40675D01*
G01X952128Y-50300D02*
Y-38634D01*
G01Y-40675D02*
X951255Y-39509D01*
X949944Y-38925D01*
X948416Y-38634D01*
X946888Y-39217D01*
X945578Y-40383D01*
X944704Y-42133D01*
X944268Y-44467D01*
X944704Y-46800D01*
X945578Y-48550D01*
X946888Y-49717D01*
X948416Y-50300D01*
X949944Y-50008D01*
X951255Y-49134D01*
X952128Y-47967D01*
G01X961986Y-50300D02*
Y-38634D01*
G01Y-41550D02*
X962860Y-40092D01*
X964170Y-38925D01*
X965916Y-38634D01*
X967444Y-38925D01*
X968755Y-40092D01*
X969410Y-42133D01*
Y-50300D01*
G01X986691Y-40092D02*
X985163Y-38925D01*
X983853Y-38634D01*
X982106Y-39217D01*
X980796Y-40383D01*
X979923Y-42425D01*
X979704Y-44467D01*
X979923Y-46509D01*
X980796Y-48259D01*
X982106Y-49717D01*
X983853Y-50300D01*
X985381Y-49717D01*
X986691Y-48550D01*
G01X997423Y-42425D02*
X1004410D01*
X1003755Y-40383D01*
X1002663Y-39217D01*
X1001135Y-38634D01*
X999606Y-38925D01*
X998296Y-39800D01*
X997423Y-41842D01*
X996986Y-43592D01*
Y-45342D01*
X997423Y-47092D01*
X998515Y-48842D01*
X999825Y-50008D01*
X1001353Y-50300D01*
X1002881Y-49717D01*
X1004410Y-47967D01*
G01X1035698Y-32800D02*
Y-50300D01*
G01X1032641Y-38634D02*
X1038755D01*
G01X1050141Y-50300D02*
Y-38634D01*
G01Y-40967D02*
X1051233Y-39800D01*
X1052325Y-38925D01*
X1053853Y-38634D01*
X1054944Y-38925D01*
X1056255Y-39800D01*
G01X1074628Y-50300D02*
Y-38634D01*
G01Y-40675D02*
X1073755Y-39509D01*
X1072444Y-38925D01*
X1070916Y-38634D01*
X1069388Y-39217D01*
X1068078Y-40383D01*
X1067204Y-42133D01*
X1066768Y-44467D01*
X1067204Y-46800D01*
X1068078Y-48550D01*
X1069388Y-49717D01*
X1070916Y-50300D01*
X1072444Y-50008D01*
X1073755Y-49134D01*
X1074628Y-47967D01*
G01X1091691Y-40092D02*
X1090163Y-38925D01*
X1088853Y-38634D01*
X1087106Y-39217D01*
X1085796Y-40383D01*
X1084923Y-42425D01*
X1084704Y-44467D01*
X1084923Y-46509D01*
X1085796Y-48259D01*
X1087106Y-49717D01*
X1088853Y-50300D01*
X1090381Y-49717D01*
X1091691Y-48550D01*
G01X1102423Y-42425D02*
X1109410D01*
X1108755Y-40383D01*
X1107663Y-39217D01*
X1106135Y-38634D01*
X1104606Y-38925D01*
X1103296Y-39800D01*
X1102423Y-41842D01*
X1101986Y-43592D01*
Y-45342D01*
X1102423Y-47092D01*
X1103515Y-48842D01*
X1104825Y-50008D01*
X1106353Y-50300D01*
X1107881Y-49717D01*
X1109410Y-47967D01*
G01X1119923Y-48259D02*
X1121015Y-49425D01*
X1122543Y-50300D01*
X1123853D01*
X1125163Y-49717D01*
X1126036Y-48842D01*
X1126473Y-47676D01*
X1126255Y-45925D01*
X1125381Y-45050D01*
X1121451Y-43300D01*
X1120578Y-41258D01*
X1121015Y-39800D01*
X1121888Y-38925D01*
X1123198Y-38634D01*
X1124508Y-38925D01*
X1125818Y-39800D01*
G01X1158198Y-38634D02*
Y-50300D01*
G01Y-33967D02*
X1157761Y-33675D01*
Y-33092D01*
X1158198Y-32800D01*
X1158635Y-33092D01*
Y-33675D01*
X1158198Y-33967D01*
G01X1171986Y-50300D02*
Y-38634D01*
G01Y-41550D02*
X1172860Y-40092D01*
X1174170Y-38925D01*
X1175916Y-38634D01*
X1177444Y-38925D01*
X1178755Y-40092D01*
X1179410Y-42133D01*
Y-50300D01*
G01X1210698D02*
Y-32800D01*
G01X1232128Y-50300D02*
Y-38634D01*
G01Y-40675D02*
X1231255Y-39509D01*
X1229944Y-38925D01*
X1228416Y-38634D01*
X1226888Y-39217D01*
X1225578Y-40383D01*
X1224704Y-42133D01*
X1224268Y-44467D01*
X1224704Y-46800D01*
X1225578Y-48550D01*
X1226888Y-49717D01*
X1228416Y-50300D01*
X1229944Y-50008D01*
X1231255Y-49134D01*
X1232128Y-47967D01*
G01X1241113Y-55550D02*
X1242423Y-56133D01*
X1244170Y-55550D01*
X1245261Y-54384D01*
X1246135Y-52925D01*
X1247444Y-48259D01*
X1250283Y-38634D01*
G01X1243296D02*
X1247444Y-48259D01*
G01X1259923Y-42425D02*
X1266910D01*
X1266255Y-40383D01*
X1265163Y-39217D01*
X1263635Y-38634D01*
X1262106Y-38925D01*
X1260796Y-39800D01*
X1259923Y-41842D01*
X1259486Y-43592D01*
Y-45342D01*
X1259923Y-47092D01*
X1261015Y-48842D01*
X1262325Y-50008D01*
X1263853Y-50300D01*
X1265381Y-49717D01*
X1266910Y-47967D01*
G01X1277641Y-50300D02*
Y-38634D01*
G01Y-40967D02*
X1278733Y-39800D01*
X1279825Y-38925D01*
X1281353Y-38634D01*
X1282444Y-38925D01*
X1283755Y-39800D01*
G01X1311331Y-32800D02*
Y-50300D01*
X1320065D01*
G01X1329050Y-43009D02*
X1330578Y-40967D01*
X1331888Y-39800D01*
X1333635Y-39217D01*
X1335163Y-39800D01*
X1336255Y-40967D01*
X1337128Y-42717D01*
X1337346Y-44758D01*
X1337128Y-46509D01*
X1336255Y-48259D01*
X1334944Y-49717D01*
X1333416Y-50300D01*
X1331670Y-49717D01*
X1330141Y-47967D01*
X1329268Y-45342D01*
X1329050Y-42425D01*
X1329486Y-38634D01*
X1330141Y-36591D01*
X1331233Y-34550D01*
X1332761Y-33092D01*
X1334290Y-32800D01*
X1335818Y-33383D01*
X1336910Y-34842D01*
G01X1350698Y-50883D02*
X1350261Y-50592D01*
Y-50008D01*
X1350698Y-49717D01*
X1351135Y-50008D01*
Y-50592D01*
X1350698Y-50883D01*
G01X1201883Y1950376D02*
X1207123D01*
G01X1204503D02*
Y1932876D01*
G01X1201883D02*
X1207123D01*
G01X1216326D02*
Y1950376D01*
X1222003Y1935793D01*
X1227680Y1950376D01*
Y1932876D01*
G01X1235136D02*
Y1950376D01*
X1240376D01*
X1242123Y1949501D01*
X1243433Y1947459D01*
X1243870Y1945126D01*
X1243433Y1942793D01*
X1242341Y1941043D01*
X1240376Y1940167D01*
X1235136D01*
G01X1255911Y1927043D02*
X1253728Y1929959D01*
X1252636Y1932876D01*
Y1944542D01*
X1253728Y1947459D01*
X1255911Y1950376D01*
G01X1274503Y1932876D02*
X1272756Y1933168D01*
X1271228Y1934334D01*
X1269918Y1936084D01*
X1269044Y1938126D01*
X1268608Y1940459D01*
Y1942793D01*
X1269044Y1945126D01*
X1269918Y1947168D01*
X1271228Y1948917D01*
X1272756Y1950084D01*
X1274503Y1950376D01*
X1276249Y1950084D01*
X1277778Y1948917D01*
X1279088Y1947168D01*
X1279962Y1945126D01*
X1280398Y1942793D01*
Y1940459D01*
X1279962Y1938126D01*
X1279088Y1936084D01*
X1277778Y1934334D01*
X1276249Y1933168D01*
X1274503Y1932876D01*
G01X1288291D02*
Y1950376D01*
G01Y1941918D02*
X1289383Y1943376D01*
X1290475Y1944251D01*
X1292221Y1944542D01*
X1293531Y1944251D01*
X1295060Y1943084D01*
X1295715Y1941334D01*
Y1932876D01*
G01X1302953D02*
Y1944542D01*
G01Y1941334D02*
X1303608Y1942793D01*
X1304700Y1943959D01*
X1306228Y1944542D01*
X1307756Y1943959D01*
X1308848Y1942793D01*
X1309503Y1941334D01*
Y1932876D01*
G01Y1941334D02*
X1310158Y1942793D01*
X1311249Y1943959D01*
X1312778Y1944542D01*
X1314306Y1943959D01*
X1315398Y1942793D01*
X1316053Y1941043D01*
Y1932876D01*
G01X1328095Y1927043D02*
X1330278Y1929959D01*
X1331370Y1932876D01*
Y1944542D01*
X1330278Y1947459D01*
X1328095Y1950376D01*
G01X1180000Y1967526D02*
Y1985026D01*
X1184366D01*
X1186113Y1984151D01*
X1187423Y1982984D01*
X1188515Y1981235D01*
X1189388Y1979192D01*
X1189606Y1976276D01*
X1189388Y1973359D01*
X1188515Y1971317D01*
X1187423Y1969567D01*
X1186113Y1968401D01*
X1184366Y1967526D01*
X1180000D01*
G01X1197936D02*
Y1985026D01*
X1203176D01*
X1204923Y1984151D01*
X1206233Y1982109D01*
X1206670Y1979776D01*
X1206233Y1977443D01*
X1205141Y1975693D01*
X1203176Y1974817D01*
X1197936D01*
G01X1234683Y1985026D02*
X1239923D01*
G01X1237303D02*
Y1967526D01*
G01X1234683D02*
X1239923D01*
G01X1249126D02*
Y1985026D01*
X1254803Y1970443D01*
X1260480Y1985026D01*
Y1967526D01*
G01X1267936D02*
Y1985026D01*
X1273176D01*
X1274923Y1984151D01*
X1276233Y1982109D01*
X1276670Y1979776D01*
X1276233Y1977443D01*
X1275141Y1975693D01*
X1273176Y1974817D01*
X1267936D01*
G01X1294170Y1967526D02*
X1285436D01*
Y1985026D01*
X1294170D01*
G01X1290676Y1976568D02*
X1285436D01*
G01X1302500Y1967526D02*
Y1985026D01*
X1306866D01*
X1308613Y1984151D01*
X1309923Y1982984D01*
X1311015Y1981235D01*
X1311888Y1979192D01*
X1312106Y1976276D01*
X1311888Y1973359D01*
X1311015Y1971317D01*
X1309923Y1969567D01*
X1308613Y1968401D01*
X1306866Y1967526D01*
X1302500D01*
G01X1319344D02*
X1324803Y1985026D01*
X1330262Y1967526D01*
G01X1328296Y1973651D02*
X1321309D01*
G01X1337281Y1967526D02*
Y1985026D01*
X1347325Y1967526D01*
Y1985026D01*
G01X1364606Y1983567D02*
X1363296Y1984443D01*
X1361768Y1985026D01*
X1360021D01*
X1358056Y1984151D01*
X1356528Y1982693D01*
X1355436Y1980942D01*
X1354563Y1978026D01*
X1354344Y1975401D01*
X1354781Y1972776D01*
X1355436Y1971026D01*
X1356746Y1969276D01*
X1358275Y1968109D01*
X1359803Y1967526D01*
X1361331D01*
X1362860Y1968109D01*
X1364170Y1968984D01*
X1365262Y1970150D01*
G01X1381670Y1967526D02*
X1372936D01*
Y1985026D01*
X1381670D01*
G01X1378176Y1976568D02*
X1372936D01*
G01X1412303Y1985026D02*
Y1967526D01*
G01X1407281Y1985026D02*
X1417325D01*
G01X1424344Y1967526D02*
X1429803Y1985026D01*
X1435262Y1967526D01*
G01X1433296Y1973651D02*
X1426309D01*
G01X1449049Y1976859D02*
X1449923Y1977734D01*
X1450578Y1979192D01*
X1451015Y1981235D01*
X1450578Y1982984D01*
X1449705Y1984151D01*
X1448176Y1985026D01*
X1442281D01*
Y1967526D01*
X1449486D01*
X1451015Y1968692D01*
X1451888Y1970443D01*
X1452325Y1972484D01*
X1451888Y1974526D01*
X1450578Y1976276D01*
X1449049Y1976859D01*
X1442281D01*
G01X1460436Y1985026D02*
Y1967526D01*
X1469170D01*
G01X1486670D02*
X1477936D01*
Y1985026D01*
X1486670D01*
G01X1483176Y1976568D02*
X1477936D01*
G01X1499803Y1966943D02*
X1499366Y1967234D01*
Y1967818D01*
X1499803Y1968109D01*
X1500240Y1967818D01*
Y1967234D01*
X1499803Y1966943D01*
G01Y1974817D02*
X1499366Y1975109D01*
Y1975693D01*
X1499803Y1975984D01*
X1500240Y1975693D01*
Y1975109D01*
X1499803Y1974817D01*
G01X1530436Y1985026D02*
Y1967526D01*
X1539170D01*
G01X1548155Y1974817D02*
X1549683Y1976859D01*
X1550993Y1978026D01*
X1552740Y1978609D01*
X1554268Y1978026D01*
X1555360Y1976859D01*
X1556233Y1975109D01*
X1556451Y1973068D01*
X1556233Y1971317D01*
X1555360Y1969567D01*
X1554049Y1968109D01*
X1552521Y1967526D01*
X1550775Y1968109D01*
X1549246Y1969859D01*
X1548373Y1972484D01*
X1548155Y1975401D01*
X1548591Y1979192D01*
X1549246Y1981235D01*
X1550338Y1983276D01*
X1551866Y1984734D01*
X1553395Y1985026D01*
X1554923Y1984443D01*
X1556015Y1982984D01*
G01X1217200Y1862993D02*
X1226806Y1875826D01*
G01X1222003Y1878159D02*
Y1860659D01*
G01X1226806Y1862993D02*
X1217200Y1875826D01*
G01X1215453Y1869409D02*
X1228553D01*
G01X1239503Y1863576D02*
Y1881076D01*
X1236883Y1877576D01*
G01Y1863576D02*
X1242123D01*
G01X1257003Y1881076D02*
X1255256Y1880493D01*
X1253946Y1879034D01*
X1253073Y1877285D01*
X1252418Y1874951D01*
X1252200Y1872326D01*
X1252418Y1869701D01*
X1253073Y1867367D01*
X1253946Y1865617D01*
X1255256Y1864159D01*
X1257003Y1863576D01*
X1258749Y1864159D01*
X1260060Y1865617D01*
X1260933Y1867367D01*
X1261588Y1869701D01*
X1261806Y1872326D01*
X1261588Y1874951D01*
X1260933Y1877285D01*
X1260060Y1879034D01*
X1258749Y1880493D01*
X1257003Y1881076D01*
G01X1274503D02*
X1272756Y1880493D01*
X1271446Y1879034D01*
X1270573Y1877285D01*
X1269918Y1874951D01*
X1269700Y1872326D01*
X1269918Y1869701D01*
X1270573Y1867367D01*
X1271446Y1865617D01*
X1272756Y1864159D01*
X1274503Y1863576D01*
X1276249Y1864159D01*
X1277560Y1865617D01*
X1278433Y1867367D01*
X1279088Y1869701D01*
X1279306Y1872326D01*
X1279088Y1874951D01*
X1278433Y1877285D01*
X1277560Y1879034D01*
X1276249Y1880493D01*
X1274503Y1881076D01*
G01X1292003Y1862993D02*
X1291566Y1863284D01*
Y1863868D01*
X1292003Y1864159D01*
X1292440Y1863868D01*
Y1863284D01*
X1292003Y1862993D01*
G01X1309503Y1881076D02*
X1307756Y1880493D01*
X1306446Y1879034D01*
X1305573Y1877285D01*
X1304918Y1874951D01*
X1304700Y1872326D01*
X1304918Y1869701D01*
X1305573Y1867367D01*
X1306446Y1865617D01*
X1307756Y1864159D01*
X1309503Y1863576D01*
X1311249Y1864159D01*
X1312560Y1865617D01*
X1313433Y1867367D01*
X1314088Y1869701D01*
X1314306Y1872326D01*
X1314088Y1874951D01*
X1313433Y1877285D01*
X1312560Y1879034D01*
X1311249Y1880493D01*
X1309503Y1881076D01*
G01X1239503Y1898226D02*
X1241031Y1898518D01*
X1242778Y1899392D01*
X1243870Y1900850D01*
X1244306Y1902893D01*
X1243870Y1904934D01*
X1242560Y1906684D01*
X1240595Y1907559D01*
X1238411D01*
X1237101Y1908143D01*
X1236009Y1909601D01*
X1235573Y1911642D01*
X1236228Y1913684D01*
X1237756Y1915143D01*
X1239503Y1915726D01*
X1241249Y1915143D01*
X1242778Y1913684D01*
X1243433Y1911642D01*
X1242996Y1909601D01*
X1241905Y1908143D01*
X1240595Y1907559D01*
X1238411D01*
X1236446Y1906684D01*
X1235136Y1904934D01*
X1234700Y1902893D01*
X1235136Y1900850D01*
X1236228Y1899392D01*
X1237975Y1898518D01*
X1239503Y1898226D01*
G01X1252200Y1900850D02*
X1253509Y1899392D01*
X1255038Y1898518D01*
X1257003Y1898226D01*
X1258968Y1898809D01*
X1260496Y1899976D01*
X1261588Y1902017D01*
X1261806Y1904351D01*
X1261370Y1906684D01*
X1260278Y1908143D01*
X1258749Y1909309D01*
X1257221Y1909601D01*
X1255693Y1909309D01*
X1253728Y1908143D01*
X1254383Y1915726D01*
X1260278D01*
G01X1274503Y1897643D02*
X1274066Y1897934D01*
Y1898518D01*
X1274503Y1898809D01*
X1274940Y1898518D01*
Y1897934D01*
X1274503Y1897643D01*
G01X1292003Y1915726D02*
X1290256Y1915143D01*
X1288946Y1913684D01*
X1288073Y1911935D01*
X1287418Y1909601D01*
X1287200Y1906976D01*
X1287418Y1904351D01*
X1288073Y1902017D01*
X1288946Y1900267D01*
X1290256Y1898809D01*
X1292003Y1898226D01*
X1293749Y1898809D01*
X1295060Y1900267D01*
X1295933Y1902017D01*
X1296588Y1904351D01*
X1296806Y1906976D01*
X1296588Y1909601D01*
X1295933Y1911935D01*
X1295060Y1913684D01*
X1293749Y1915143D01*
X1292003Y1915726D01*
G01X1407953Y1950376D02*
X1411009Y1932876D01*
X1414503Y1950376D01*
X1417996Y1932876D01*
X1421053Y1950376D01*
G01X1429383D02*
X1434623D01*
G01X1432003D02*
Y1932876D01*
G01X1429383D02*
X1434623D01*
G01X1444700D02*
Y1950376D01*
X1449066D01*
X1450813Y1949501D01*
X1452123Y1948334D01*
X1453215Y1946585D01*
X1454088Y1944542D01*
X1454306Y1941626D01*
X1454088Y1938709D01*
X1453215Y1936667D01*
X1452123Y1934917D01*
X1450813Y1933751D01*
X1449066Y1932876D01*
X1444700D01*
G01X1467003Y1950376D02*
Y1932876D01*
G01X1461981Y1950376D02*
X1472025D01*
G01X1479918Y1932876D02*
Y1950376D01*
G01X1489088D02*
Y1932876D01*
G01Y1941626D02*
X1479918D01*
G01X1500911Y1927043D02*
X1498728Y1929959D01*
X1497636Y1932876D01*
Y1944542D01*
X1498728Y1947459D01*
X1500911Y1950376D01*
G01X1512953Y1932876D02*
Y1944542D01*
G01Y1941334D02*
X1513608Y1942793D01*
X1514700Y1943959D01*
X1516228Y1944542D01*
X1517756Y1943959D01*
X1518848Y1942793D01*
X1519503Y1941334D01*
Y1932876D01*
G01Y1941334D02*
X1520158Y1942793D01*
X1521249Y1943959D01*
X1522778Y1944542D01*
X1524306Y1943959D01*
X1525398Y1942793D01*
X1526053Y1941043D01*
Y1932876D01*
G01X1537003Y1944542D02*
Y1932876D01*
G01Y1949209D02*
X1536566Y1949501D01*
Y1950084D01*
X1537003Y1950376D01*
X1537440Y1950084D01*
Y1949501D01*
X1537003Y1949209D01*
G01X1554503Y1932876D02*
Y1950376D01*
G01X1568728Y1934917D02*
X1569820Y1933751D01*
X1571348Y1932876D01*
X1572658D01*
X1573968Y1933459D01*
X1574841Y1934334D01*
X1575278Y1935500D01*
X1575060Y1937251D01*
X1574186Y1938126D01*
X1570256Y1939876D01*
X1569383Y1941918D01*
X1569820Y1943376D01*
X1570693Y1944251D01*
X1572003Y1944542D01*
X1573313Y1944251D01*
X1574623Y1943376D01*
G01X1590595Y1927043D02*
X1592778Y1929959D01*
X1593870Y1932876D01*
Y1944542D01*
X1592778Y1947459D01*
X1590595Y1950376D01*
G01X1452123Y1863576D02*
Y1881076D01*
X1444044Y1868534D01*
X1454962D01*
G01X1467003Y1862993D02*
X1466566Y1863284D01*
Y1863868D01*
X1467003Y1864159D01*
X1467440Y1863868D01*
Y1863284D01*
X1467003Y1862993D01*
G01X1479700Y1866200D02*
X1481009Y1864742D01*
X1482538Y1863868D01*
X1484503Y1863576D01*
X1486468Y1864159D01*
X1487996Y1865326D01*
X1489088Y1867367D01*
X1489306Y1869701D01*
X1488870Y1872034D01*
X1487778Y1873493D01*
X1486249Y1874659D01*
X1484721Y1874951D01*
X1483193Y1874659D01*
X1481228Y1873493D01*
X1481883Y1881076D01*
X1487778D01*
G01X1498073Y1862993D02*
X1505933Y1881076D01*
G01X1515791Y1865617D02*
X1517320Y1864159D01*
X1519066Y1863576D01*
X1520813Y1864159D01*
X1522341Y1865909D01*
X1523433Y1868534D01*
X1523870Y1871159D01*
Y1874367D01*
X1523433Y1876992D01*
X1522341Y1879326D01*
X1521031Y1880493D01*
X1519503Y1881076D01*
X1517756Y1880493D01*
X1516446Y1879326D01*
X1515573Y1877576D01*
X1515136Y1875242D01*
X1515573Y1873201D01*
X1516665Y1871159D01*
X1517975Y1869992D01*
X1519503Y1869701D01*
X1521249Y1870284D01*
X1522560Y1871743D01*
X1523870Y1874367D01*
G01X1537003Y1862993D02*
X1536566Y1863284D01*
Y1863868D01*
X1537003Y1864159D01*
X1537440Y1863868D01*
Y1863284D01*
X1537003Y1862993D01*
G01X1554503Y1881076D02*
X1552756Y1880493D01*
X1551446Y1879034D01*
X1550573Y1877285D01*
X1549918Y1874951D01*
X1549700Y1872326D01*
X1549918Y1869701D01*
X1550573Y1867367D01*
X1551446Y1865617D01*
X1552756Y1864159D01*
X1554503Y1863576D01*
X1556249Y1864159D01*
X1557560Y1865617D01*
X1558433Y1867367D01*
X1559088Y1869701D01*
X1559306Y1872326D01*
X1559088Y1874951D01*
X1558433Y1877285D01*
X1557560Y1879034D01*
X1556249Y1880493D01*
X1554503Y1881076D01*
G01X1445355Y1905517D02*
X1446883Y1907559D01*
X1448193Y1908726D01*
X1449940Y1909309D01*
X1451468Y1908726D01*
X1452560Y1907559D01*
X1453433Y1905809D01*
X1453651Y1903768D01*
X1453433Y1902017D01*
X1452560Y1900267D01*
X1451249Y1898809D01*
X1449721Y1898226D01*
X1447975Y1898809D01*
X1446446Y1900559D01*
X1445573Y1903184D01*
X1445355Y1906101D01*
X1445791Y1909892D01*
X1446446Y1911935D01*
X1447538Y1913976D01*
X1449066Y1915434D01*
X1450595Y1915726D01*
X1452123Y1915143D01*
X1453215Y1913684D01*
G01X1467003Y1897643D02*
X1466566Y1897934D01*
Y1898518D01*
X1467003Y1898809D01*
X1467440Y1898518D01*
Y1897934D01*
X1467003Y1897643D01*
G01X1479700Y1900850D02*
X1481009Y1899392D01*
X1482538Y1898518D01*
X1484503Y1898226D01*
X1486468Y1898809D01*
X1487996Y1899976D01*
X1489088Y1902017D01*
X1489306Y1904351D01*
X1488870Y1906684D01*
X1487778Y1908143D01*
X1486249Y1909309D01*
X1484721Y1909601D01*
X1483193Y1909309D01*
X1481228Y1908143D01*
X1481883Y1915726D01*
X1487778D01*
G01X1498073Y1897643D02*
X1505933Y1915726D01*
G01X1519066Y1898226D02*
X1519503Y1902017D01*
X1520158Y1905226D01*
X1521031Y1908143D01*
X1522123Y1911351D01*
X1523870Y1915726D01*
X1515136D01*
G01X1537003Y1897643D02*
X1536566Y1897934D01*
Y1898518D01*
X1537003Y1898809D01*
X1537440Y1898518D01*
Y1897934D01*
X1537003Y1897643D01*
G01X1549700Y1900850D02*
X1551009Y1899392D01*
X1552538Y1898518D01*
X1554503Y1898226D01*
X1556468Y1898809D01*
X1557996Y1899976D01*
X1559088Y1902017D01*
X1559306Y1904351D01*
X1558870Y1906684D01*
X1557778Y1908143D01*
X1556249Y1909309D01*
X1554721Y1909601D01*
X1553193Y1909309D01*
X1551228Y1908143D01*
X1551883Y1915726D01*
X1557778D01*
G01X1689700Y1863576D02*
Y1881076D01*
X1694066D01*
X1695813Y1880201D01*
X1697123Y1879034D01*
X1698215Y1877285D01*
X1699088Y1875242D01*
X1699306Y1872326D01*
X1699088Y1869409D01*
X1698215Y1867367D01*
X1697123Y1865617D01*
X1695813Y1864451D01*
X1694066Y1863576D01*
X1689700D01*
G01X1707636D02*
Y1881076D01*
X1712876D01*
X1714623Y1880201D01*
X1715933Y1878159D01*
X1716370Y1875826D01*
X1715933Y1873493D01*
X1714841Y1871743D01*
X1712876Y1870867D01*
X1707636D01*
G01X1677003Y1950376D02*
Y1932876D01*
G01X1671981Y1950376D02*
X1682025D01*
G01X1694503Y1932876D02*
Y1940751D01*
X1690136Y1950376D01*
G01X1698870D02*
X1694503Y1940751D01*
G01X1707636Y1932876D02*
Y1950376D01*
X1712876D01*
X1714623Y1949501D01*
X1715933Y1947459D01*
X1716370Y1945126D01*
X1715933Y1942793D01*
X1714841Y1941043D01*
X1712876Y1940167D01*
X1707636D01*
G01X1733870Y1932876D02*
X1725136D01*
Y1950376D01*
X1733870D01*
G01X1730376Y1941918D02*
X1725136D01*
G01X1689700Y1898226D02*
Y1915726D01*
X1694066D01*
X1695813Y1914851D01*
X1697123Y1913684D01*
X1698215Y1911935D01*
X1699088Y1909892D01*
X1699306Y1906976D01*
X1699088Y1904059D01*
X1698215Y1902017D01*
X1697123Y1900267D01*
X1695813Y1899101D01*
X1694066Y1898226D01*
X1689700D01*
G01X1707636D02*
Y1915726D01*
X1712876D01*
X1714623Y1914851D01*
X1715933Y1912809D01*
X1716370Y1910476D01*
X1715933Y1908143D01*
X1714841Y1906393D01*
X1712876Y1905517D01*
X1707636D01*
G01X1777636Y1932876D02*
Y1950376D01*
X1783095D01*
X1784841Y1949501D01*
X1785933Y1948334D01*
X1786370Y1946001D01*
X1785933Y1943667D01*
X1784623Y1942209D01*
X1783095Y1941334D01*
X1777636D01*
G01X1783095D02*
X1786370Y1932876D01*
G01X1796228Y1940751D02*
X1803215D01*
X1802560Y1942793D01*
X1801468Y1943959D01*
X1799940Y1944542D01*
X1798411Y1944251D01*
X1797101Y1943376D01*
X1796228Y1941334D01*
X1795791Y1939584D01*
Y1937834D01*
X1796228Y1936084D01*
X1797320Y1934334D01*
X1798630Y1933168D01*
X1800158Y1932876D01*
X1801686Y1933459D01*
X1803215Y1935209D01*
G01X1815693Y1932876D02*
Y1947751D01*
X1816130Y1949209D01*
X1817003Y1950084D01*
X1818313Y1950376D01*
X1819623Y1949793D01*
X1820278Y1948334D01*
G01X1817658Y1943376D02*
X1813291D01*
G01X1834503Y1932293D02*
X1834066Y1932584D01*
Y1933168D01*
X1834503Y1933459D01*
X1834940Y1933168D01*
Y1932584D01*
X1834503Y1932293D01*
G01X1865136Y1932876D02*
Y1950376D01*
X1870376D01*
X1872123Y1949501D01*
X1873433Y1947459D01*
X1873870Y1945126D01*
X1873433Y1942793D01*
X1872341Y1941043D01*
X1870376Y1940167D01*
X1865136D01*
G01X1887003Y1932876D02*
Y1950376D01*
G01X1908433Y1932876D02*
Y1944542D01*
G01Y1942501D02*
X1907560Y1943667D01*
X1906249Y1944251D01*
X1904721Y1944542D01*
X1903193Y1943959D01*
X1901883Y1942793D01*
X1901009Y1941043D01*
X1900573Y1938709D01*
X1901009Y1936376D01*
X1901883Y1934626D01*
X1903193Y1933459D01*
X1904721Y1932876D01*
X1906249Y1933168D01*
X1907560Y1934042D01*
X1908433Y1935209D01*
G01X1918291Y1932876D02*
Y1944542D01*
G01Y1941626D02*
X1919165Y1943084D01*
X1920475Y1944251D01*
X1922221Y1944542D01*
X1923749Y1944251D01*
X1925060Y1943084D01*
X1925715Y1941043D01*
Y1932876D01*
G01X1936228Y1940751D02*
X1943215D01*
X1942560Y1942793D01*
X1941468Y1943959D01*
X1939940Y1944542D01*
X1938411Y1944251D01*
X1937101Y1943376D01*
X1936228Y1941334D01*
X1935791Y1939584D01*
Y1937834D01*
X1936228Y1936084D01*
X1937320Y1934334D01*
X1938630Y1933168D01*
X1940158Y1932876D01*
X1941686Y1933459D01*
X1943215Y1935209D01*
G01X1821386Y1881076D02*
Y1863576D01*
X1830120D01*
G01X1838450Y1866200D02*
X1839759Y1864742D01*
X1841288Y1863868D01*
X1843253Y1863576D01*
X1845218Y1864159D01*
X1846746Y1865326D01*
X1847838Y1867367D01*
X1848056Y1869701D01*
X1847620Y1872034D01*
X1846528Y1873493D01*
X1844999Y1874659D01*
X1843471Y1874951D01*
X1841943Y1874659D01*
X1839978Y1873493D01*
X1840633Y1881076D01*
X1846528D01*
G01X1856823Y1862993D02*
X1864683Y1881076D01*
G01X1873886D02*
Y1863576D01*
X1882620D01*
G01X1895316D02*
X1895753Y1867367D01*
X1896408Y1870576D01*
X1897281Y1873493D01*
X1898373Y1876701D01*
X1900120Y1881076D01*
X1891386D01*
G01X1821386Y1915726D02*
Y1898226D01*
X1830120D01*
G01X1838450Y1900850D02*
X1839759Y1899392D01*
X1841288Y1898518D01*
X1843253Y1898226D01*
X1845218Y1898809D01*
X1846746Y1899976D01*
X1847838Y1902017D01*
X1848056Y1904351D01*
X1847620Y1906684D01*
X1846528Y1908143D01*
X1844999Y1909309D01*
X1843471Y1909601D01*
X1841943Y1909309D01*
X1839978Y1908143D01*
X1840633Y1915726D01*
X1846528D01*
G01X1856823Y1897643D02*
X1864683Y1915726D01*
G01X1873886D02*
Y1898226D01*
X1882620D01*
G01X1895316D02*
X1895753Y1902017D01*
X1896408Y1905226D01*
X1897281Y1908143D01*
X1898373Y1911351D01*
X1900120Y1915726D01*
X1891386D01*
G01X1982500Y1932293D02*
X1992106Y1945126D01*
G01X1987303Y1947459D02*
Y1929959D01*
G01X1992106Y1932293D02*
X1982500Y1945126D01*
G01X1980753Y1938709D02*
X1993853D01*
G01X2019465D02*
X2025141D01*
G01X2052500Y1932876D02*
Y1950376D01*
X2056866D01*
X2058613Y1949501D01*
X2059923Y1948334D01*
X2061015Y1946585D01*
X2061888Y1944542D01*
X2062106Y1941626D01*
X2061888Y1938709D01*
X2061015Y1936667D01*
X2059923Y1934917D01*
X2058613Y1933751D01*
X2056866Y1932876D01*
X2052500D01*
G01X2071528Y1940751D02*
X2078515D01*
X2077860Y1942793D01*
X2076768Y1943959D01*
X2075240Y1944542D01*
X2073711Y1944251D01*
X2072401Y1943376D01*
X2071528Y1941334D01*
X2071091Y1939584D01*
Y1937834D01*
X2071528Y1936084D01*
X2072620Y1934334D01*
X2073930Y1933168D01*
X2075458Y1932876D01*
X2076986Y1933459D01*
X2078515Y1935209D01*
G01X2088591Y1932876D02*
Y1944542D01*
G01Y1941626D02*
X2089465Y1943084D01*
X2090775Y1944251D01*
X2092521Y1944542D01*
X2094049Y1944251D01*
X2095360Y1943084D01*
X2096015Y1941043D01*
Y1932876D01*
G01X2109803D02*
X2108493Y1933168D01*
X2107183Y1934334D01*
X2106309Y1936376D01*
X2105873Y1938709D01*
X2106309Y1941043D01*
X2107183Y1943084D01*
X2108493Y1944251D01*
X2109803Y1944542D01*
X2111113Y1944251D01*
X2112423Y1943084D01*
X2113296Y1941043D01*
X2113515Y1938709D01*
X2113296Y1936376D01*
X2112423Y1934334D01*
X2111113Y1933168D01*
X2109803Y1932876D01*
G01X2127303Y1950376D02*
Y1932876D01*
G01X2124246Y1944542D02*
X2130360D01*
G01X2141528Y1940751D02*
X2148515D01*
X2147860Y1942793D01*
X2146768Y1943959D01*
X2145240Y1944542D01*
X2143711Y1944251D01*
X2142401Y1943376D01*
X2141528Y1941334D01*
X2141091Y1939584D01*
Y1937834D01*
X2141528Y1936084D01*
X2142620Y1934334D01*
X2143930Y1933168D01*
X2145458Y1932876D01*
X2146986Y1933459D01*
X2148515Y1935209D01*
G01X2159028Y1934917D02*
X2160120Y1933751D01*
X2161648Y1932876D01*
X2162958D01*
X2164268Y1933459D01*
X2165141Y1934334D01*
X2165578Y1935500D01*
X2165360Y1937251D01*
X2164486Y1938126D01*
X2160556Y1939876D01*
X2159683Y1941918D01*
X2160120Y1943376D01*
X2160993Y1944251D01*
X2162303Y1944542D01*
X2163613Y1944251D01*
X2164923Y1943376D01*
G01X2197303Y1950376D02*
Y1932876D01*
G01X2194246Y1944542D02*
X2200360D01*
G01X2211091Y1932876D02*
Y1950376D01*
G01Y1941918D02*
X2212183Y1943376D01*
X2213275Y1944251D01*
X2215021Y1944542D01*
X2216331Y1944251D01*
X2217860Y1943084D01*
X2218515Y1941334D01*
Y1932876D01*
G01X2236233D02*
Y1944542D01*
G01Y1942501D02*
X2235360Y1943667D01*
X2234049Y1944251D01*
X2232521Y1944542D01*
X2230993Y1943959D01*
X2229683Y1942793D01*
X2228809Y1941043D01*
X2228373Y1938709D01*
X2228809Y1936376D01*
X2229683Y1934626D01*
X2230993Y1933459D01*
X2232521Y1932876D01*
X2234049Y1933168D01*
X2235360Y1934042D01*
X2236233Y1935209D01*
G01X2249803Y1950376D02*
Y1932876D01*
G01X2246746Y1944542D02*
X2252860D01*
G01X2284803Y1950376D02*
Y1932876D01*
G01X2281746Y1944542D02*
X2287860D01*
G01X2298591Y1932876D02*
Y1950376D01*
G01Y1941918D02*
X2299683Y1943376D01*
X2300775Y1944251D01*
X2302521Y1944542D01*
X2303831Y1944251D01*
X2305360Y1943084D01*
X2306015Y1941334D01*
Y1932876D01*
G01X2319803Y1944542D02*
Y1932876D01*
G01Y1949209D02*
X2319366Y1949501D01*
Y1950084D01*
X2319803Y1950376D01*
X2320240Y1950084D01*
Y1949501D01*
X2319803Y1949209D01*
G01X2334028Y1934917D02*
X2335120Y1933751D01*
X2336648Y1932876D01*
X2337958D01*
X2339268Y1933459D01*
X2340141Y1934334D01*
X2340578Y1935500D01*
X2340360Y1937251D01*
X2339486Y1938126D01*
X2335556Y1939876D01*
X2334683Y1941918D01*
X2335120Y1943376D01*
X2335993Y1944251D01*
X2337303Y1944542D01*
X2338613Y1944251D01*
X2339923Y1943376D01*
G01X2369683Y1950376D02*
X2374923D01*
G01X2372303D02*
Y1932876D01*
G01X2369683D02*
X2374923D01*
G01X2383253D02*
Y1944542D01*
G01Y1941334D02*
X2383908Y1942793D01*
X2385000Y1943959D01*
X2386528Y1944542D01*
X2388056Y1943959D01*
X2389148Y1942793D01*
X2389803Y1941334D01*
Y1932876D01*
G01Y1941334D02*
X2390458Y1942793D01*
X2391549Y1943959D01*
X2393078Y1944542D01*
X2394606Y1943959D01*
X2395698Y1942793D01*
X2396353Y1941043D01*
Y1932876D01*
G01X2403373Y1927043D02*
Y1944542D01*
G01Y1941918D02*
X2404465Y1943376D01*
X2405556Y1944251D01*
X2407303Y1944542D01*
X2408831Y1944251D01*
X2410360Y1942793D01*
X2411015Y1940751D01*
X2411233Y1938709D01*
X2411015Y1936667D01*
X2410360Y1934626D01*
X2409049Y1933459D01*
X2407303Y1932876D01*
X2405775Y1933168D01*
X2404246Y1934042D01*
X2403373Y1935209D01*
G01X2421528Y1940751D02*
X2428515D01*
X2427860Y1942793D01*
X2426768Y1943959D01*
X2425240Y1944542D01*
X2423711Y1944251D01*
X2422401Y1943376D01*
X2421528Y1941334D01*
X2421091Y1939584D01*
Y1937834D01*
X2421528Y1936084D01*
X2422620Y1934334D01*
X2423930Y1933168D01*
X2425458Y1932876D01*
X2426986Y1933459D01*
X2428515Y1935209D01*
G01X2446233Y1950376D02*
Y1932876D01*
G01Y1935500D02*
X2445360Y1934042D01*
X2444049Y1933168D01*
X2442521Y1932876D01*
X2440775Y1933459D01*
X2439465Y1934917D01*
X2438591Y1936667D01*
X2438373Y1938709D01*
X2438591Y1940751D01*
X2439465Y1942501D01*
X2440775Y1943959D01*
X2442521Y1944542D01*
X2444049Y1944251D01*
X2445141Y1943667D01*
X2446233Y1942501D01*
G01X2463733Y1932876D02*
Y1944542D01*
G01Y1942501D02*
X2462860Y1943667D01*
X2461549Y1944251D01*
X2460021Y1944542D01*
X2458493Y1943959D01*
X2457183Y1942793D01*
X2456309Y1941043D01*
X2455873Y1938709D01*
X2456309Y1936376D01*
X2457183Y1934626D01*
X2458493Y1933459D01*
X2460021Y1932876D01*
X2461549Y1933168D01*
X2462860Y1934042D01*
X2463733Y1935209D01*
G01X2473591Y1932876D02*
Y1944542D01*
G01Y1941626D02*
X2474465Y1943084D01*
X2475775Y1944251D01*
X2477521Y1944542D01*
X2479049Y1944251D01*
X2480360Y1943084D01*
X2481015Y1941043D01*
Y1932876D01*
G01X2498296Y1943084D02*
X2496768Y1944251D01*
X2495458Y1944542D01*
X2493711Y1943959D01*
X2492401Y1942793D01*
X2491528Y1940751D01*
X2491309Y1938709D01*
X2491528Y1936667D01*
X2492401Y1934917D01*
X2493711Y1933459D01*
X2495458Y1932876D01*
X2496986Y1933459D01*
X2498296Y1934626D01*
G01X2509028Y1940751D02*
X2516015D01*
X2515360Y1942793D01*
X2514268Y1943959D01*
X2512740Y1944542D01*
X2511211Y1944251D01*
X2509901Y1943376D01*
X2509028Y1941334D01*
X2508591Y1939584D01*
Y1937834D01*
X2509028Y1936084D01*
X2510120Y1934334D01*
X2511430Y1933168D01*
X2512958Y1932876D01*
X2514486Y1933459D01*
X2516015Y1935209D01*
G01X2057303Y1909892D02*
Y1898226D01*
G01Y1914559D02*
X2056866Y1914851D01*
Y1915434D01*
X2057303Y1915726D01*
X2057740Y1915434D01*
Y1914851D01*
X2057303Y1914559D01*
G01X2071528Y1900267D02*
X2072620Y1899101D01*
X2074148Y1898226D01*
X2075458D01*
X2076768Y1898809D01*
X2077641Y1899684D01*
X2078078Y1900850D01*
X2077860Y1902601D01*
X2076986Y1903476D01*
X2073056Y1905226D01*
X2072183Y1907268D01*
X2072620Y1908726D01*
X2073493Y1909601D01*
X2074803Y1909892D01*
X2076113Y1909601D01*
X2077423Y1908726D01*
G01X2104781Y1898226D02*
Y1915726D01*
X2114825Y1898226D01*
Y1915726D01*
G01X2127303Y1898226D02*
X2125556Y1898518D01*
X2124028Y1899684D01*
X2122718Y1901434D01*
X2121844Y1903476D01*
X2121408Y1905809D01*
Y1908143D01*
X2121844Y1910476D01*
X2122718Y1912518D01*
X2124028Y1914267D01*
X2125556Y1915434D01*
X2127303Y1915726D01*
X2129049Y1915434D01*
X2130578Y1914267D01*
X2131888Y1912518D01*
X2132762Y1910476D01*
X2133198Y1908143D01*
Y1905809D01*
X2132762Y1903476D01*
X2131888Y1901434D01*
X2130578Y1899684D01*
X2129049Y1898518D01*
X2127303Y1898226D01*
G01X2144803Y1915726D02*
Y1898226D01*
G01X2139781Y1915726D02*
X2149825D01*
G01X2176091Y1909892D02*
Y1901726D01*
X2176965Y1899684D01*
X2178275Y1898518D01*
X2179803Y1898226D01*
X2181331Y1898518D01*
X2182641Y1899684D01*
X2183515Y1901726D01*
G01Y1898226D02*
Y1909892D01*
G01X2194028Y1900267D02*
X2195120Y1899101D01*
X2196648Y1898226D01*
X2197958D01*
X2199268Y1898809D01*
X2200141Y1899684D01*
X2200578Y1900850D01*
X2200360Y1902601D01*
X2199486Y1903476D01*
X2195556Y1905226D01*
X2194683Y1907268D01*
X2195120Y1908726D01*
X2195993Y1909601D01*
X2197303Y1909892D01*
X2198613Y1909601D01*
X2199923Y1908726D01*
G01X2211528Y1906101D02*
X2218515D01*
X2217860Y1908143D01*
X2216768Y1909309D01*
X2215240Y1909892D01*
X2213711Y1909601D01*
X2212401Y1908726D01*
X2211528Y1906684D01*
X2211091Y1904934D01*
Y1903184D01*
X2211528Y1901434D01*
X2212620Y1899684D01*
X2213930Y1898518D01*
X2215458Y1898226D01*
X2216986Y1898809D01*
X2218515Y1900559D01*
G01X2236233Y1915726D02*
Y1898226D01*
G01Y1900850D02*
X2235360Y1899392D01*
X2234049Y1898518D01*
X2232521Y1898226D01*
X2230775Y1898809D01*
X2229465Y1900267D01*
X2228591Y1902017D01*
X2228373Y1904059D01*
X2228591Y1906101D01*
X2229465Y1907851D01*
X2230775Y1909309D01*
X2232521Y1909892D01*
X2234049Y1909601D01*
X2235141Y1909017D01*
X2236233Y1907851D01*
G01X-7874Y0D02*
X-75552D01*
G02X-90552Y15000I0J15000D01*
G01Y519024D01*
G02X-75552Y534024I15000J0D01*
G01X-7874D01*
G01Y1030087D02*
X-75552D01*
G03X-90552Y1015087I0J-15000D01*
G01Y1001780D01*
G03X-75552Y986780I15000J0D01*
G01X-7874D01*
G01Y1992126D02*
X-75552D01*
G03X-90552Y1977126I0J-15000D01*
G01Y1915165D01*
G03X-75552Y1900165I15000J0D01*
G01X-7874D01*
G01X1023228Y1618051D02*
Y1675945D01*
G02X1028701Y1681417I5472J0D01*
G01X1033465D01*
X1037402Y1685354D01*
Y1988189D01*
G03X1033465Y1992126I-3937J0D01*
G01X3937D01*
G03X0Y1988189I0J-3937D01*
G01Y1661189D01*
X1969Y1659220D01*
X17323D01*
G02Y1650559I0J-4331D01*
G01X1969D01*
X0Y1648591D01*
Y1243866D01*
X1969Y1241898D01*
X17323D01*
G02Y1233236I0J-4331D01*
G01X1969D01*
X0Y1231268D01*
Y747803D01*
X1969Y745835D01*
X17323D01*
G02Y737173I0J-4331D01*
G01X1969D01*
X0Y735205D01*
Y3937D01*
G03X3937Y0I3937J0D01*
G01X121260D01*
X127310Y11888D01*
G03X127953Y14567I-5263J2680D01*
G01Y17717D01*
G02X139764I5906J0D01*
G01Y14567D01*
G03X140406Y11888I5906J-1D01*
G01X146457Y0D01*
X1033465D01*
G03X1037402Y3937I0J3937D01*
G01Y1424882D01*
X1033465Y1428819D01*
X1028701D01*
G02X1023228Y1434291I0J5473D01*
G01Y1609902D01*
X1021260Y1611870D01*
X993681D01*
G02Y1616083I0J2107D01*
G01X1021260D01*
X1023228Y1618051D01*
G01X-7874Y39059D02*
G03X0I3937J0D01*
G01Y8350D02*
G03X-7874I-3937J0D01*
G01D02*
Y0D01*
G01Y251657D02*
Y39059D01*
G01X0Y251657D02*
G03X-7874I-3937J0D01*
G01Y282366D02*
G03X0I3937J0D01*
G01X-7874Y494965D02*
Y282366D01*
G01Y525673D02*
G03X0I3937J0D01*
G01Y494965D02*
G03X-7874I-3937J0D01*
G01Y534024D02*
Y525673D01*
G01X0Y993079D02*
G03X-7874I-3937J0D01*
G01Y986780D02*
Y993079D01*
G01Y1023787D02*
G03X0I3937J0D01*
G01X-7874D02*
Y1030087D01*
G01Y1930791D02*
Y1900165D01*
G01X0Y1930791D02*
G03X-7874I-3937J0D01*
G01Y1961500D02*
G03X0I3937J0D01*
G01X-7874Y1992126D02*
Y1961500D01*
G01X1045276Y0D02*
X1112953D01*
G03X1127953Y15000I0J15000D01*
G01Y493259D01*
G01X1045276Y25827D02*
G03X1037402I-3937J0D01*
G01X1045276Y0D02*
Y25827D01*
G01X1037402Y56535D02*
G03X1045276I3937J0D01*
G01D02*
Y284882D01*
G01X1037402Y315591D02*
G03X1045276I3937J0D01*
G01Y284882D02*
G03X1037402I-3937J0D01*
G01X1045276Y315591D02*
Y543937D01*
G01D02*
G03X1037402I-3937J0D01*
G01Y574646D02*
G03X1045276I3937J0D01*
G01D02*
Y802992D01*
G01X1037402Y833701D02*
G03X1045276I3937J0D01*
G01Y802992D02*
G03X1037402I-3937J0D01*
G01X1045276Y833701D02*
Y1062047D01*
G01D02*
G03X1037402I-3937J0D01*
G01Y1092756D02*
G03X1045276I3937J0D01*
G01D02*
Y1321102D01*
G01D02*
G03X1037402I-3937J0D01*
G01Y1351811D02*
G03X1045276I3937J0D01*
G01D02*
Y1377638D01*
G01D02*
X1112953D01*
G02X1127953Y1362638I0J-15000D01*
G01Y501133D01*
G01X1045276Y1732598D02*
X1112953D01*
G03X1127953Y1747598I0J15000D01*
G01Y1977126D01*
G03X1112953Y1992126I-15000J0D01*
G01X1045276D01*
G01X1037402Y1767835D02*
G03X1045276I3937J0D01*
G01Y1737126D02*
G03X1037402I-3937J0D01*
G01X1045276Y1767835D02*
Y1956890D01*
G01Y1732598D02*
Y1737126D01*
G01X1037402Y1987598D02*
G03X1045276I3937J0D01*
G01Y1956890D02*
G03X1037402I-3937J0D01*
G01X1045276Y1987598D02*
Y1992126D01*
G01X1127953Y501133D02*
G03Y493259I0J-3937D01*
G54D12*
G01X46314Y343583D02*
X32127Y423982D01*
G01X44989Y343034D02*
X30705Y423982D01*
G01X44989Y343034D02*
X30705Y423982D01*
G01X46314Y343583D02*
X32127Y423982D01*
G01X37834Y345554D02*
X102083Y253795D01*
G01X36509Y345005D02*
X100758Y253246D01*
G01X26189Y411590D02*
X37834Y345554D01*
G01X24767Y411590D02*
X36509Y345005D01*
G01D02*
X100758Y253246D01*
G01X37834Y345554D02*
X102083Y253795D01*
G01X24767Y411590D02*
X36509Y345005D01*
G01X26189Y411590D02*
X37834Y345554D01*
G01X32127Y423982D02*
X54965Y553465D01*
G01X30705Y423982D02*
X53543Y553465D01*
G01X30705Y423982D02*
X53543Y553465D01*
G01X32127Y423982D02*
X54965Y553465D01*
G01X49658Y544721D02*
X26189Y411590D01*
G01X25594Y416280D02*
X24767Y411590D01*
G01X26528Y421577D02*
X26189Y419657D01*
G01X48236Y544721D02*
X27123Y424955D01*
G01X25594Y416280D02*
X24767Y411590D01*
G01X49658Y544721D02*
X26189Y411590D01*
G01X26528Y421577D02*
X26189Y419657D01*
G01X49658Y544721D02*
X26189Y411590D01*
G01X48236Y544721D02*
X27123Y424955D01*
G01X49658Y544721D02*
X26189Y411590D01*
G01X28989Y629019D02*
X28429D01*
G01X28866Y627619D02*
X28429D01*
G01X30901Y628682D02*
X28989Y629019D01*
G01X28866Y627619D02*
X28429D01*
G01X30352Y627357D02*
X28866Y627619D01*
G01X44471Y619185D02*
X30901Y628682D01*
G01X31950Y626239D02*
X30352Y627357D01*
G01X34760Y624272D02*
X33729Y624090D01*
G01X36357Y623154D02*
X34760Y624272D01*
G01X39167Y621187D02*
X38137Y621005D01*
G01X28866Y627619D02*
X28429D01*
G01X28989Y629019D02*
X28429D01*
G01X30901Y628682D02*
X28989Y629019D01*
G01X30352Y627357D02*
X28866Y627619D01*
G01X30901Y628682D02*
X28989Y629019D01*
G01X31950Y626239D02*
X30352Y627357D01*
G01X44471Y619185D02*
X30901Y628682D01*
G01X34760Y624272D02*
X33729Y624090D01*
G01X44471Y619185D02*
X30901Y628682D01*
G01X36357Y623154D02*
X34760Y624272D01*
G01X44471Y619185D02*
X30901Y628682D01*
G01X39167Y621187D02*
X38137Y621005D01*
G01X44471Y619185D02*
X30901Y628682D01*
G01X44471Y619185D02*
X30901Y628682D01*
G01X30246Y616371D02*
X28429D01*
G01X30123Y614971D02*
X28429D01*
G01X34624Y615601D02*
X30246Y616371D01*
G01X34075Y614275D02*
X30123Y614971D01*
G01X36894Y614011D02*
X34624Y615601D01*
G01X35888Y613005D02*
X34075Y614275D01*
G01X46781Y599892D02*
X36894Y614011D01*
G01X37007Y611408D02*
X35888Y613005D01*
G01X30123Y614971D02*
X28429D01*
G01X30246Y616371D02*
X28429D01*
G01X34075Y614275D02*
X30123Y614971D01*
G01X34624Y615601D02*
X30246Y616371D01*
G01X35888Y613005D02*
X34075Y614275D01*
G01X36894Y614011D02*
X34624Y615601D01*
G01X37007Y611408D02*
X35888Y613005D01*
G01X46781Y599892D02*
X36894Y614011D01*
G01X46781Y599892D02*
X36894Y614011D01*
G01X46781Y599892D02*
X36894Y614011D01*
G01X37429Y600059D02*
X40737Y595331D01*
G01X36423Y599053D02*
X39412Y594782D01*
G01X33086Y603099D02*
X37429Y600059D01*
G01X32537Y601774D02*
X36423Y599053D01*
G01X30944Y603477D02*
X33086Y603099D01*
G01X28865Y602422D02*
X32537Y601774D01*
G01X28988Y603822D02*
X30944Y603477D01*
G01X28865Y602422D02*
X32537Y601774D01*
G01X28429Y602422D02*
X28865D01*
G01X28429Y603822D02*
X28988D01*
G01X28429Y602422D02*
X28865D01*
G01X36423Y599053D02*
X39412Y594782D01*
G01X37429Y600059D02*
X40737Y595331D01*
G01X32537Y601774D02*
X36423Y599053D01*
G01X33086Y603099D02*
X37429Y600059D01*
G01X28865Y602422D02*
X32537Y601774D01*
G01X30944Y603477D02*
X33086Y603099D01*
G01X28988Y603822D02*
X30944Y603477D01*
G01X28429Y602422D02*
X28865D01*
G01X28988Y603822D02*
X30944Y603477D01*
G01X28429Y603822D02*
X28988D01*
G01X28865Y703210D02*
X49798Y699521D01*
G01X28989Y641618D02*
X28429D01*
G01Y640218D02*
X28866D01*
G01X34944Y640568D02*
X28989Y641618D01*
G01X28866Y640218D02*
X34395Y639243D01*
G01X28429Y640218D02*
X28866D01*
G01X41525Y635961D02*
X34944Y640568D01*
G01X34395Y639243D02*
X40519Y634955D01*
G01X34395Y639243D02*
X40519Y634955D01*
G01X41525Y635961D02*
X34944Y640568D01*
G01X28866Y640218D02*
X34395Y639243D01*
G01X34944Y640568D02*
X28989Y641618D01*
G01X28429Y640218D02*
X28866D01*
G01X28989Y641618D02*
X28429D01*
G01X34944Y640568D02*
X28989Y641618D01*
G01X28865Y703210D02*
X49798Y699521D01*
G01X28990Y692011D02*
X28429D01*
G01X28867Y690611D02*
X28429D01*
G01X71367Y684533D02*
X28990Y692011D01*
G01X28867Y690611D02*
X28429D01*
G01X30787Y690272D02*
X28867Y690611D01*
G01X36085Y689337D02*
X34165Y689676D01*
G01X28867Y690611D02*
X28429D01*
G01X28990Y692011D02*
X28429D01*
G01X71367Y684533D02*
X28990Y692011D01*
G01X30787Y690272D02*
X28867Y690611D01*
G01X71367Y684533D02*
X28990Y692011D01*
G01X36085Y689337D02*
X34165Y689676D01*
G01X71367Y684533D02*
X28990Y692011D01*
G01X71367Y684533D02*
X28990Y692011D01*
G01X71367Y684533D02*
X28990Y692011D01*
G01X28988Y679413D02*
X28429D01*
G01X28865Y678013D02*
X28429D01*
G01X78647Y670659D02*
X28988Y679413D01*
G01X28865Y678013D02*
X28429D01*
G01X30785Y677674D02*
X28865Y678013D01*
G01X36084Y676740D02*
X34163Y677079D01*
G01X28865Y678013D02*
X28429D01*
G01X28988Y679413D02*
X28429D01*
G01X78647Y670659D02*
X28988Y679413D01*
G01X30785Y677674D02*
X28865Y678013D01*
G01X78647Y670659D02*
X28988Y679413D01*
G01X36084Y676740D02*
X34163Y677079D01*
G01X78647Y670659D02*
X28988Y679413D01*
G01X78647Y670659D02*
X28988Y679413D01*
G01X78647Y670659D02*
X28988Y679413D01*
G01X78647Y670659D02*
X28988Y679413D01*
G01X78647Y670659D02*
X28988Y679413D01*
G01X31011Y666815D02*
X28429D01*
G01Y665415D02*
X31134D01*
G01X37305Y667925D02*
X31011Y666815D01*
G01X31134Y665415D02*
X37305Y666503D01*
G01X81078Y660206D02*
X37305Y667925D01*
G01Y666503D02*
X61986Y662150D01*
G01X81078Y660206D02*
X37305Y667925D01*
G01X81078Y660206D02*
X37305Y667925D01*
G01Y666503D02*
X61986Y662150D01*
G01X81078Y660206D02*
X37305Y667925D01*
G01X31134Y665415D02*
X37305Y666503D01*
G01Y667925D02*
X31011Y666815D01*
G01X28429Y665415D02*
X31134D01*
G01X31011Y666815D02*
X28429D01*
G01X30246Y773701D02*
X28429D01*
G01X30123Y772301D02*
X28429D01*
G01X41156Y771778D02*
X30246Y773701D01*
G01X40607Y770453D02*
X30123Y772301D01*
G01D02*
X28429D01*
G01X30246Y773701D02*
X28429D01*
G01X40607Y770453D02*
X30123Y772301D01*
G01X41156Y771778D02*
X30246Y773701D01*
G01X28988Y704610D02*
X62979Y698620D01*
G01X28429Y703210D02*
X28865D01*
G01X28429Y704610D02*
X28988D01*
G01X28429Y703210D02*
X28865D01*
G01X30246Y761103D02*
X40086Y759368D01*
G01X39537Y758043D02*
X30123Y759703D01*
G01X28429Y761103D02*
X30246D01*
G01X30123Y759703D02*
X28429D01*
G01X30123D02*
X28429D01*
G01Y761103D02*
X30246D01*
G01X39537Y758043D02*
X30123Y759703D01*
G01X30246Y761103D02*
X40086Y759368D01*
G01X30246Y729607D02*
X63249Y723789D01*
G01X62700Y722464D02*
X30123Y728207D01*
G01X28429Y729607D02*
X30246D01*
G01X30123Y728207D02*
X28429D01*
G01X30123D02*
X28429D01*
G01Y729607D02*
X30246D01*
G01X62700Y722464D02*
X30123Y728207D01*
G01X30246Y729607D02*
X63249Y723789D01*
G01X30246Y717008D02*
X60102Y711744D01*
G01X30123Y715608D02*
X59553Y710419D01*
G01X28429Y717008D02*
X30246D01*
G01X28429Y715608D02*
X30123D01*
G01D02*
X59553Y710419D01*
G01X30246Y717008D02*
X60102Y711744D01*
G01X28429Y715608D02*
X30123D01*
G01X28429Y717008D02*
X30246D01*
G01X28988Y704610D02*
X62979Y698620D01*
G01X28988Y704610D02*
X62979Y698620D01*
G01X28988Y704610D02*
X62979Y698620D01*
G01X28429Y703210D02*
X28865D01*
G01X28988Y704610D02*
X62979Y698620D01*
G01X28429Y704610D02*
X28988D01*
G01X38793Y829094D02*
X45668Y819276D01*
G01X44343Y818727D02*
X37787Y828088D01*
G01X33173Y833028D02*
X38793Y829094D01*
G01X37787Y828088D02*
X32624Y831703D01*
G01X30246Y833544D02*
X33173Y833028D01*
G01X32624Y831703D02*
X30123Y832144D01*
G01X28429Y833544D02*
X30246D01*
G01X30123Y832144D02*
X28429D01*
G01X30123D02*
X28429D01*
G01Y833544D02*
X30246D01*
G01X32624Y831703D02*
X30123Y832144D01*
G01X30246Y833544D02*
X33173Y833028D01*
G01X37787Y828088D02*
X32624Y831703D01*
G01X33173Y833028D02*
X38793Y829094D01*
G01X44343Y818727D02*
X37787Y828088D01*
G01X38793Y829094D02*
X45668Y819276D01*
G01X37119Y818167D02*
X41497Y811913D01*
G01X40172Y811364D02*
X36113Y817161D01*
G01X34126Y820261D02*
X37119Y818167D01*
G01X36113Y817161D02*
X33577Y818936D01*
G01X30246Y820945D02*
X34126Y820261D01*
G01X33577Y818936D02*
X30123Y819545D01*
G01X28429Y820945D02*
X30246D01*
G01X30123Y819545D02*
X28429D01*
G01X30123D02*
X28429D01*
G01Y820945D02*
X30246D01*
G01X33577Y818936D02*
X30123Y819545D01*
G01X30246Y820945D02*
X34126Y820261D01*
G01X36113Y817161D02*
X33577Y818936D01*
G01X34126Y820261D02*
X37119Y818167D01*
G01X40172Y811364D02*
X36113Y817161D01*
G01X37119Y818167D02*
X41497Y811913D01*
G01X38285Y805611D02*
X130156Y674396D01*
G01X129150Y673390D02*
X37279Y804605D01*
G01X35762Y807376D02*
X38285Y805611D01*
G01X37279Y804605D02*
X35213Y806051D01*
G01X30246Y808347D02*
X35762Y807376D01*
G01X35213Y806051D02*
X30123Y806947D01*
G01X28429Y808347D02*
X30246D01*
G01X30123Y806947D02*
X28429D01*
G01X30123D02*
X28429D01*
G01Y808347D02*
X30246D01*
G01X35213Y806051D02*
X30123Y806947D01*
G01X30246Y808347D02*
X35762Y807376D01*
G01X37279Y804605D02*
X35213Y806051D01*
G01X35762Y807376D02*
X38285Y805611D01*
G01X129150Y673390D02*
X37279Y804605D01*
G01X38285Y805611D02*
X130156Y674396D01*
G01X30246Y795748D02*
X28429D01*
G01X30123Y794348D02*
X28429D01*
G01X36506Y794644D02*
X30246Y795748D01*
G01X35957Y793319D02*
X30123Y794348D01*
G01X46014Y787987D02*
X36506Y794644D01*
G01X45009Y786980D02*
X35957Y793319D01*
G01X30123Y794348D02*
X28429D01*
G01X30246Y795748D02*
X28429D01*
G01X35957Y793319D02*
X30123Y794348D01*
G01X36506Y794644D02*
X30246Y795748D01*
G01X45009Y786980D02*
X35957Y793319D01*
G01X46014Y787987D02*
X36506Y794644D01*
G01X34457Y845199D02*
X41696Y840132D01*
G01X33907Y843874D02*
X40692Y839124D01*
G01X30246Y845942D02*
X34457Y845199D01*
G01X30123Y844542D02*
X33907Y843874D01*
G01X28429Y845942D02*
X30246D01*
G01X28429Y844542D02*
X30123D01*
G01X33907Y843874D02*
X40692Y839124D01*
G01X34457Y845199D02*
X41696Y840132D01*
G01X30123Y844542D02*
X33907Y843874D01*
G01X30246Y845942D02*
X34457Y845199D01*
G01X28429Y844542D02*
X30123D01*
G01X28429Y845942D02*
X30246D01*
G01X37925Y882434D02*
X50382Y873694D01*
G01X49376Y872689D02*
X37375Y881108D01*
G01X30246Y883787D02*
X37925Y882434D01*
G01X33749Y881748D02*
X30123Y882387D01*
G01X37376Y881109D02*
X33749Y881748D01*
G01X28429Y883787D02*
X30246D01*
G01X30123Y882387D02*
X28429D01*
G01X30123D02*
X28429D01*
G01Y883787D02*
X30246D01*
G01X33749Y881748D02*
X30123Y882387D01*
G01X30246Y883787D02*
X37925Y882434D01*
G01X37376Y881109D02*
X33749Y881748D01*
G01X30246Y883787D02*
X37925Y882434D01*
G01X49376Y872689D02*
X37375Y881108D01*
G01X37925Y882434D02*
X50382Y873694D01*
G01X37925Y882434D02*
X50382Y873694D01*
G01X38336Y869713D02*
X39875Y868635D01*
G01X37785Y868388D02*
X39196Y867400D01*
G01X30246Y871139D02*
X38336Y869713D01*
G01X30123Y869739D02*
X37785Y868388D01*
G01X28429Y871139D02*
X30246D01*
G01X28429Y869739D02*
X30123D01*
G01X37785Y868388D02*
X39196Y867400D01*
G01X38336Y869713D02*
X39875Y868635D01*
G01X30123Y869739D02*
X37785Y868388D01*
G01X30246Y871139D02*
X38336Y869713D01*
G01X28429Y869739D02*
X30123D01*
G01X28429Y871139D02*
X30246D01*
G01X37311Y912838D02*
X45795Y924954D01*
G01X38317Y911832D02*
X47120Y924405D01*
G01X32662Y909582D02*
X37311Y912838D01*
G01X33211Y908257D02*
X38314Y911829D01*
G01X30123Y909134D02*
X32662Y909582D01*
G01X30246Y907734D02*
X33211Y908257D01*
G01X28429Y909134D02*
X30123D01*
G01X28429Y907734D02*
X30246D01*
G01X38317Y911832D02*
X47120Y924405D01*
G01X37311Y912838D02*
X45795Y924954D01*
G01X33211Y908257D02*
X38314Y911829D01*
G01X32662Y909582D02*
X37311Y912838D01*
G01X30246Y907734D02*
X33211Y908257D01*
G01X30123Y909134D02*
X32662Y909582D01*
G01X28429Y907734D02*
X30246D01*
G01X28429Y909134D02*
X30123D01*
G01X30246Y858541D02*
X28429D01*
G01X30123Y857141D02*
X28429D01*
G01X36160Y857498D02*
X30246Y858541D01*
G01X35610Y856173D02*
X30123Y857141D01*
G01X35611Y856173D02*
X35610D01*
G01X41081Y854052D02*
X36160Y857498D01*
G01X35611Y856173D02*
X35610D01*
G01X36844Y855309D02*
X35611Y856173D01*
G01X36845Y855309D02*
X36844D01*
G01X40075Y853047D02*
X36845Y855309D01*
G01X30123Y857141D02*
X28429D01*
G01X30246Y858541D02*
X28429D01*
G01X35610Y856173D02*
X30123Y857141D01*
G01X36160Y857498D02*
X30246Y858541D01*
G01X35611Y856173D02*
X35610D01*
G01X36160Y857498D02*
X30246Y858541D01*
G01X41081Y854052D02*
X36160Y857498D01*
G01X36844Y855309D02*
X35611Y856173D01*
G01X41081Y854052D02*
X36160Y857498D01*
G01X36845Y855309D02*
X36844D01*
G01X41081Y854052D02*
X36160Y857498D01*
G01X40075Y853047D02*
X36845Y855309D01*
G01X41081Y854052D02*
X36160Y857498D01*
G01X35217Y898808D02*
X54886Y926897D01*
G01X36223Y897802D02*
X56211Y926348D01*
G01X35218Y898808D02*
X35217D01*
G01X33142Y895646D02*
X36223Y897802D01*
G01X34890Y898580D02*
X35218Y898808D01*
G01X33142Y895646D02*
X36223Y897802D01*
G01X34562Y898349D02*
X34890Y898580D01*
G01X33142Y895646D02*
X36223Y897802D01*
G01X34007Y897961D02*
X34562Y898349D01*
G01X33142Y895646D02*
X36223Y897802D01*
G01X33905Y897889D02*
X34007Y897961D01*
G01X33142Y895646D02*
X36223Y897802D01*
G01X32593Y896971D02*
X33905Y897889D01*
G01X33142Y895646D02*
X36223Y897802D01*
G01X30123Y896536D02*
X32593Y896971D01*
G01X30246Y895136D02*
X33142Y895646D01*
G01X28429Y896536D02*
X30123D01*
G01X28429Y895136D02*
X30246D01*
G01X36223Y897802D02*
X56211Y926348D01*
G01X35217Y898808D02*
X54886Y926897D01*
G01X33142Y895646D02*
X36223Y897802D01*
G01X35218Y898808D02*
X35217D01*
G01X34890Y898580D02*
X35218Y898808D01*
G01X34562Y898349D02*
X34890Y898580D01*
G01X34007Y897961D02*
X34562Y898349D01*
G01X33905Y897889D02*
X34007Y897961D01*
G01X32593Y896971D02*
X33905Y897889D01*
G01X30246Y895136D02*
X33142Y895646D01*
G01X30123Y896536D02*
X32593Y896971D01*
G01X28429Y895136D02*
X30246D01*
G01X28429Y896536D02*
X30123D01*
G01X28988Y1112484D02*
X28429D01*
G01X28865Y1111084D02*
X28429D01*
G01X51571Y1108504D02*
X28988Y1112484D01*
G01X28865Y1111084D02*
X28429D01*
G01X51022Y1107179D02*
X28865Y1111084D01*
G01D02*
X28429D01*
G01X28988Y1112484D02*
X28429D01*
G01X51571Y1108504D02*
X28988Y1112484D01*
G01X51022Y1107179D02*
X28865Y1111084D01*
G01X51571Y1108504D02*
X28988Y1112484D01*
G01Y1099885D02*
X28429D01*
G01X28865Y1098485D02*
X28429D01*
G01X51961Y1095836D02*
X28988Y1099885D01*
G01X28865Y1098485D02*
X28429D01*
G01X51412Y1094511D02*
X28865Y1098485D01*
G01D02*
X28429D01*
G01X28988Y1099885D02*
X28429D01*
G01X51961Y1095836D02*
X28988Y1099885D01*
G01X51412Y1094511D02*
X28865Y1098485D01*
G01X51961Y1095836D02*
X28988Y1099885D01*
G01X30246Y1137481D02*
X28429D01*
G01X30123Y1136081D02*
X28429D01*
G01X40806Y1135619D02*
X30246Y1137481D01*
G01X40257Y1134294D02*
X30123Y1136081D01*
G01D02*
X28429D01*
G01X30246Y1137481D02*
X28429D01*
G01X40257Y1134294D02*
X30123Y1136081D01*
G01X40806Y1135619D02*
X30246Y1137481D01*
G01X35784Y1174224D02*
X61447Y1156255D01*
G01X35235Y1172899D02*
X60441Y1155249D01*
G01X29805Y1175276D02*
X35784Y1174224D01*
G01X29682Y1173876D02*
X35235Y1172899D01*
G01X28429Y1175276D02*
X29805D01*
G01X28429Y1173876D02*
X29682D01*
G01X35235Y1172899D02*
X60441Y1155249D01*
G01X35784Y1174224D02*
X61447Y1156255D01*
G01X29682Y1173876D02*
X35235Y1172899D01*
G01X29805Y1175276D02*
X35784Y1174224D01*
G01X28429Y1173876D02*
X29682D01*
G01X28429Y1175276D02*
X29805D01*
G01X30123Y1211671D02*
X28429D01*
G01X36461Y1210554D02*
X30123Y1211671D01*
G01X45375Y1206024D02*
X37010Y1211879D01*
G01X44372Y1205015D02*
X36461Y1210554D01*
G01X30123Y1211671D02*
X28429D01*
G01X36461Y1210554D02*
X30123Y1211671D01*
G01X44372Y1205015D02*
X36461Y1210554D01*
G01X45375Y1206024D02*
X37010Y1211879D01*
G01X36150Y1164011D02*
X46766Y1162138D01*
G01X36175Y1162584D02*
X46217Y1160813D01*
G01X29876Y1162678D02*
X36150Y1164011D01*
G01X30023Y1161278D02*
X36175Y1162584D01*
G01X28429Y1162678D02*
X29876D01*
G01X28429Y1161278D02*
X30023D01*
G01X36175Y1162584D02*
X46217Y1160813D01*
G01X36150Y1164011D02*
X46766Y1162138D01*
G01X30023Y1161278D02*
X36175Y1162584D01*
G01X29876Y1162678D02*
X36150Y1164011D01*
G01X28429Y1161278D02*
X30023D01*
G01X28429Y1162678D02*
X29876D01*
G01X30246Y1200473D02*
X28429D01*
G01X30123Y1199073D02*
X28429D01*
G01X34168Y1199782D02*
X30246Y1200473D01*
G01X33619Y1198457D02*
X30123Y1199073D01*
G01X52825Y1186719D02*
X34168Y1199782D01*
G01X51820Y1185712D02*
X33619Y1198457D01*
G01X30123Y1199073D02*
X28429D01*
G01X30246Y1200473D02*
X28429D01*
G01X33619Y1198457D02*
X30123Y1199073D01*
G01X34168Y1199782D02*
X30246Y1200473D01*
G01X51820Y1185712D02*
X33619Y1198457D01*
G01X52825Y1186719D02*
X34168Y1199782D01*
G01X30586Y1150079D02*
X42332Y1152575D01*
G01X30734Y1148679D02*
X42332Y1151143D01*
G01X28429Y1150079D02*
X30586D01*
G01X28429Y1148679D02*
X30734D01*
G01D02*
X42332Y1151143D01*
G01X30586Y1150079D02*
X42332Y1152575D01*
G01X28429Y1148679D02*
X30734D01*
G01X28429Y1150079D02*
X30586D01*
G01X30246Y1187874D02*
X28429D01*
G01X30123Y1186474D02*
X28429D01*
G01X39347Y1186269D02*
X30246Y1187874D01*
G01X38797Y1184944D02*
X30123Y1186474D01*
G01X42764Y1182166D02*
X38797Y1184944D01*
G01X30123Y1186474D02*
X28429D01*
G01X30246Y1187874D02*
X28429D01*
G01X38797Y1184944D02*
X30123Y1186474D01*
G01X39347Y1186269D02*
X30246Y1187874D01*
G01X42764Y1182166D02*
X38797Y1184944D01*
G01X30246Y1225670D02*
X28429D01*
G01X30123Y1224270D02*
X28429D01*
G01X35244Y1224790D02*
X30246Y1225670D01*
G01X34695Y1223465D02*
X30123Y1224270D01*
G01X39241Y1221992D02*
X35244Y1224790D01*
G01X38236Y1220985D02*
X34695Y1223465D01*
G01X99144Y1134001D02*
X38236Y1220985D01*
G01X30123Y1224270D02*
X28429D01*
G01X30246Y1225670D02*
X28429D01*
G01X34695Y1223465D02*
X30123Y1224270D01*
G01X35244Y1224790D02*
X30246Y1225670D01*
G01X38236Y1220985D02*
X34695Y1223465D01*
G01X39241Y1221992D02*
X35244Y1224790D01*
G01X99144Y1134001D02*
X38236Y1220985D01*
G01X30246Y1282363D02*
X28429D01*
G01X30123Y1280963D02*
X28429D01*
G01X34236Y1281660D02*
X30246Y1282363D01*
G01X33687Y1280335D02*
X30123Y1280963D01*
G01X43553Y1275136D02*
X34279Y1281630D01*
G01X42547Y1274130D02*
X33687Y1280335D01*
G01X30123Y1280963D02*
X28429D01*
G01X30246Y1282363D02*
X28429D01*
G01X33687Y1280335D02*
X30123Y1280963D01*
G01X34236Y1281660D02*
X30246Y1282363D01*
G01X42547Y1274130D02*
X33687Y1280335D01*
G01X43553Y1275136D02*
X34279Y1281630D01*
G01X43553Y1275136D02*
X34279Y1281630D01*
G01X30246Y1269764D02*
X28429D01*
G01X30123Y1268364D02*
X28429D01*
G01X33162Y1269251D02*
X30246Y1269764D01*
G01X32613Y1267926D02*
X30123Y1268364D01*
G01X41320Y1263540D02*
X33162Y1269251D01*
G01X40315Y1262533D02*
X32613Y1267926D01*
G01X30123Y1268364D02*
X28429D01*
G01X30246Y1269764D02*
X28429D01*
G01X32613Y1267926D02*
X30123Y1268364D01*
G01X33162Y1269251D02*
X30246Y1269764D01*
G01X40315Y1262533D02*
X32613Y1267926D01*
G01X41320Y1263540D02*
X33162Y1269251D01*
G01X33236Y1256639D02*
X41112Y1251125D01*
G01X40106Y1250119D02*
X32687Y1255314D01*
G01X30246Y1257166D02*
X33236Y1256639D01*
G01X32687Y1255314D02*
X30123Y1255766D01*
G01X28429Y1257166D02*
X30246D01*
G01X30123Y1255766D02*
X28429D01*
G01X30123D02*
X28429D01*
G01Y1257166D02*
X30246D01*
G01X32687Y1255314D02*
X30123Y1255766D01*
G01X30246Y1257166D02*
X33236Y1256639D01*
G01X40106Y1250119D02*
X32687Y1255314D01*
G01X33236Y1256639D02*
X41112Y1251125D01*
G01X30246Y1213071D02*
X28429D01*
G01X37010Y1211879D02*
X30246Y1213071D01*
G01D02*
X28429D01*
G01X37010Y1211879D02*
X30246Y1213071D01*
G01X32916Y1294469D02*
X43911Y1286768D01*
G01X34394Y1291724D02*
X42905Y1285762D01*
G01X32325Y1293173D02*
X34394Y1291724D01*
G01X32324Y1293173D02*
X32325D01*
G01X30246Y1294961D02*
X32873Y1294498D01*
G01X32324Y1293173D02*
X32325D01*
G01X30123Y1293561D02*
X32324Y1293173D01*
G01X28429Y1294961D02*
X30246D01*
G01X28429Y1293561D02*
X30123D01*
G01X34394Y1291724D02*
X42905Y1285762D01*
G01X32916Y1294469D02*
X43911Y1286768D01*
G01X32325Y1293173D02*
X34394Y1291724D01*
G01X32916Y1294469D02*
X43911Y1286768D01*
G01X32324Y1293173D02*
X32325D01*
G01X32916Y1294469D02*
X43911Y1286768D01*
G01X30246Y1294961D02*
X32873Y1294498D01*
G01X30123Y1293561D02*
X32324Y1293173D01*
G01X30246Y1294961D02*
X32873Y1294498D01*
G01X28429Y1293561D02*
X30123D01*
G01X28429Y1294961D02*
X30246D01*
G01X33774Y1355491D02*
X37621Y1358186D01*
G01X34323Y1354166D02*
X38627Y1357180D01*
G01X31011Y1355004D02*
X33774Y1355491D01*
G01X31134Y1353604D02*
X34323Y1354166D01*
G01X28429Y1355004D02*
X31011D01*
G01X28429Y1353604D02*
X31134D01*
G01X34323Y1354166D02*
X38627Y1357180D01*
G01X33774Y1355491D02*
X37621Y1358186D01*
G01X31134Y1353604D02*
X34323Y1354166D01*
G01X31011Y1355004D02*
X33774Y1355491D01*
G01X28429Y1353604D02*
X31134D01*
G01X28429Y1355004D02*
X31011D01*
G01X37095Y1343856D02*
X62678Y1380397D01*
G01X39166Y1344373D02*
X38048Y1342776D01*
G01X36078Y1343319D02*
X37095Y1343856D01*
G01X38048Y1342776D02*
X36537Y1341978D01*
G01X30889Y1342405D02*
X36078Y1343319D01*
G01X36537Y1341978D02*
X31012Y1341005D01*
G01X28429Y1342405D02*
X30889D01*
G01X31012Y1341005D02*
X28429D01*
G01X31012D02*
X28429D01*
G01Y1342405D02*
X30889D01*
G01X36537Y1341978D02*
X31012Y1341005D01*
G01X30889Y1342405D02*
X36078Y1343319D01*
G01X38048Y1342776D02*
X36537Y1341978D01*
G01X36078Y1343319D02*
X37095Y1343856D01*
G01X39166Y1344373D02*
X38048Y1342776D01*
G01X37095Y1343856D02*
X62678Y1380397D01*
G01X37095Y1343856D02*
X62678Y1380397D01*
G01X37095Y1343856D02*
X62678Y1380397D01*
G01X37095Y1343856D02*
X62678Y1380397D01*
G01X31011Y1329807D02*
X28429D01*
G01X31134Y1328407D02*
X28429D01*
G01X36443Y1330764D02*
X31011Y1329807D01*
G01X36838Y1329412D02*
X31134Y1328407D01*
G01X38499Y1331619D02*
X36443Y1330764D01*
G01X39178Y1330384D02*
X36838Y1329412D01*
G01X42900Y1334700D02*
X38499Y1331619D01*
G01X31134Y1328407D02*
X28429D01*
G01X31011Y1329807D02*
X28429D01*
G01X36838Y1329412D02*
X31134Y1328407D01*
G01X36443Y1330764D02*
X31011Y1329807D01*
G01X39178Y1330384D02*
X36838Y1329412D01*
G01X38499Y1331619D02*
X36443Y1330764D01*
G01X42900Y1334700D02*
X38499Y1331619D01*
G01X31134Y1317208D02*
X28429D01*
G01X31257Y1315808D02*
X28429D01*
G01X35446Y1317968D02*
X31134Y1317208D01*
G01X35995Y1316643D02*
X31257Y1315808D01*
G01X49724Y1327966D02*
X35446Y1317968D01*
G01X37592Y1317761D02*
X35995Y1316643D01*
G01X38623Y1317580D02*
X37592Y1317761D01*
G01X31257Y1315808D02*
X28429D01*
G01X31134Y1317208D02*
X28429D01*
G01X35995Y1316643D02*
X31257Y1315808D01*
G01X35446Y1317968D02*
X31134Y1317208D01*
G01X37592Y1317761D02*
X35995Y1316643D01*
G01X49724Y1327966D02*
X35446Y1317968D01*
G01X38623Y1317580D02*
X37592Y1317761D01*
G01X49724Y1327966D02*
X35446Y1317968D01*
G01X49724Y1327966D02*
X35446Y1317968D01*
G01X49724Y1327966D02*
X35446Y1317968D01*
G01X49724Y1327966D02*
X35446Y1317968D01*
G01X35622Y1406189D02*
X41785Y1410502D01*
G01X36171Y1404864D02*
X42791Y1409496D01*
G01X30000Y1405197D02*
X35622Y1406189D01*
G01X30123Y1403797D02*
X36171Y1404864D01*
G01X28429Y1405197D02*
X30000D01*
G01X28429Y1403797D02*
X30123D01*
G01X36171Y1404864D02*
X42791Y1409496D01*
G01X35622Y1406189D02*
X41785Y1410502D01*
G01X30123Y1403797D02*
X36171Y1404864D01*
G01X30000Y1405197D02*
X35622Y1406189D01*
G01X28429Y1403797D02*
X30123D01*
G01X28429Y1405197D02*
X30000D01*
G01X34749Y1393419D02*
X40529Y1397466D01*
G01X35291Y1392088D02*
X41535Y1396460D01*
G01X34741Y1393413D02*
X34749Y1393419D01*
G01X35291Y1392088D02*
X41535Y1396460D01*
G01X30123Y1392599D02*
X34741Y1393413D01*
G01X30246Y1391199D02*
X35290Y1392088D01*
G01X28429Y1392599D02*
X30123D01*
G01X28429Y1391199D02*
X30246D01*
G01X35291Y1392088D02*
X41535Y1396460D01*
G01X34749Y1393419D02*
X40529Y1397466D01*
G01X34741Y1393413D02*
X34749Y1393419D01*
G01X30246Y1391199D02*
X35290Y1392088D01*
G01X30123Y1392599D02*
X34741Y1393413D01*
G01X28429Y1391199D02*
X30246D01*
G01X28429Y1392599D02*
X30123D01*
G01Y1380000D02*
X28429D01*
G01X30246Y1378600D02*
X28429D01*
G01X35306Y1380913D02*
X30123Y1380000D01*
G01X35855Y1379588D02*
X30246Y1378600D01*
G01X40339Y1384438D02*
X35306Y1380913D01*
G01X41345Y1383432D02*
X35855Y1379588D01*
G01X30246Y1378600D02*
X28429D01*
G01X30123Y1380000D02*
X28429D01*
G01X35855Y1379588D02*
X30246Y1378600D01*
G01X35306Y1380913D02*
X30123Y1380000D01*
G01X41345Y1383432D02*
X35855Y1379588D01*
G01X40339Y1384438D02*
X35306Y1380913D01*
G01X30123Y1367402D02*
X28429D01*
G01Y1366002D02*
X30246D01*
G01X33230Y1367950D02*
X30123Y1367402D01*
G01X30246Y1366002D02*
X33779Y1366625D01*
G01X33238Y1367956D02*
X33230Y1367950D01*
G01X33779Y1366625D02*
X36182Y1368308D01*
G01X35180Y1369316D02*
X33238Y1367956D01*
G01X33779Y1366625D02*
X36182Y1368308D01*
G01X44744Y1382972D02*
X35180Y1369315D01*
G01X36185Y1368308D02*
X55633Y1396081D01*
G01X36185Y1368308D02*
X55633Y1396081D01*
G01X36185Y1368308D02*
X55633Y1396081D01*
G01X44744Y1382972D02*
X35180Y1369315D01*
G01X33779Y1366625D02*
X36182Y1368308D01*
G01X33238Y1367956D02*
X33230Y1367950D01*
G01X35180Y1369316D02*
X33238Y1367956D01*
G01X30246Y1366002D02*
X33779Y1366625D01*
G01X33230Y1367950D02*
X30123Y1367402D01*
G01X28429Y1366002D02*
X30246D01*
G01X30123Y1367402D02*
X28429D01*
G01X37621Y1358186D02*
X58068Y1387387D01*
G01X38627Y1357180D02*
X39746Y1358777D01*
G01X37621Y1358186D02*
X58068Y1387387D01*
G01X37621Y1358186D02*
X58068Y1387387D01*
G01X37621Y1358186D02*
X58068Y1387387D01*
G01X38627Y1357180D02*
X39746Y1358777D01*
G01X37621Y1358186D02*
X58068Y1387387D01*
G01X32809Y1564747D02*
X73724Y1593396D01*
G01X33358Y1563422D02*
X74273Y1592071D01*
G01X31403Y1564499D02*
X32809Y1564747D01*
G01X30123Y1562852D02*
X33358Y1563422D01*
G01X30291Y1564304D02*
X31403Y1564499D01*
G01X30123Y1562852D02*
X33358Y1563422D01*
G01X30000Y1564252D02*
X30291Y1564304D01*
G01X30123Y1562852D02*
X33358Y1563422D01*
G01X28429Y1564252D02*
X30000D01*
G01X28429Y1562852D02*
X30123D01*
G01X33358Y1563422D02*
X74273Y1592071D01*
G01X32809Y1564747D02*
X73724Y1593396D01*
G01X30123Y1562852D02*
X33358Y1563422D01*
G01X31403Y1564499D02*
X32809Y1564747D01*
G01X30291Y1564304D02*
X31403Y1564499D01*
G01X30000Y1564252D02*
X30291Y1564304D01*
G01X28429Y1562852D02*
X30123D01*
G01X28429Y1564252D02*
X30000D01*
G01X31600Y1551935D02*
X89348Y1592368D01*
G01X32149Y1550610D02*
X89897Y1591043D01*
G01X30000Y1551653D02*
X31600Y1551935D01*
G01X30123Y1550253D02*
X32149Y1550610D01*
G01X28429Y1551653D02*
X30000D01*
G01X28429Y1550253D02*
X30123D01*
G01X32149Y1550610D02*
X89897Y1591043D01*
G01X31600Y1551935D02*
X89348Y1592368D01*
G01X30123Y1550253D02*
X32149Y1550610D01*
G01X30000Y1551653D02*
X31600Y1551935D01*
G01X28429Y1550253D02*
X30123D01*
G01X28429Y1551653D02*
X30000D01*
G01X35573Y1541468D02*
X47765Y1558878D01*
G01X36579Y1540462D02*
X48771Y1557872D01*
G01X32843Y1539556D02*
X35573Y1541468D01*
G01X33392Y1538231D02*
X36579Y1540462D01*
G01X30000Y1539055D02*
X32843Y1539556D01*
G01X30123Y1537655D02*
X33392Y1538231D01*
G01X28429Y1539055D02*
X30000D01*
G01X28429Y1537655D02*
X30123D01*
G01X36579Y1540462D02*
X48771Y1557872D01*
G01X35573Y1541468D02*
X47765Y1558878D01*
G01X33392Y1538231D02*
X36579Y1540462D01*
G01X32843Y1539556D02*
X35573Y1541468D01*
G01X30123Y1537655D02*
X33392Y1538231D01*
G01X30000Y1539055D02*
X32843Y1539556D01*
G01X28429Y1537655D02*
X30123D01*
G01X28429Y1539055D02*
X30000D01*
G01Y1526456D02*
X28429D01*
G01X30123Y1525056D02*
X28429D01*
G01X32289Y1526860D02*
X30000Y1526456D01*
G01X32838Y1525535D02*
X30123Y1525056D01*
G01X35718Y1529261D02*
X32289Y1526860D01*
G01X36724Y1528255D02*
X32838Y1525535D01*
G01X58042Y1561147D02*
X35718Y1529261D01*
G01X59048Y1560141D02*
X36724Y1528255D01*
G01X30123Y1525056D02*
X28429D01*
G01X30000Y1526456D02*
X28429D01*
G01X32838Y1525535D02*
X30123Y1525056D01*
G01X32289Y1526860D02*
X30000Y1526456D01*
G01X36724Y1528255D02*
X32838Y1525535D01*
G01X35718Y1529261D02*
X32289Y1526860D01*
G01X59048Y1560141D02*
X36724Y1528255D01*
G01X58042Y1561147D02*
X35718Y1529261D01*
G01X30000Y1622694D02*
X39846Y1620958D01*
G01X30123Y1624094D02*
X40396Y1622283D01*
G01X28429Y1622694D02*
X30000D01*
G01X28429Y1624094D02*
X30123D01*
G01D02*
X40396Y1622283D01*
G01X30000Y1622694D02*
X39846Y1620958D01*
G01X28429Y1624094D02*
X30123D01*
G01X28429Y1622694D02*
X30000D01*
G01Y1610096D02*
X44945Y1612730D01*
G01Y1614152D02*
X29877Y1611496D01*
G01X28429Y1610096D02*
X30000D01*
G01X29877Y1611496D02*
X28429D01*
G01X29877D02*
X28429D01*
G01Y1610096D02*
X30000D01*
G01X44945Y1614152D02*
X29877Y1611496D01*
G01X30000Y1610096D02*
X44945Y1612730D01*
G01X30123Y1597497D02*
X28429D01*
G01Y1598897D02*
X30000D01*
G01X70475Y1604612D02*
X30123Y1597497D01*
G01X30000Y1598897D02*
X70475Y1606034D01*
G01X30000Y1598897D02*
X70475Y1606034D01*
G01Y1604612D02*
X30123Y1597497D01*
G01X28429Y1598897D02*
X30000D01*
G01X30123Y1597497D02*
X28429D01*
G01X30123Y1584899D02*
X28429D01*
G01Y1586299D02*
X30000D01*
G01X51180Y1588613D02*
X30123Y1584899D01*
G01X30000Y1586299D02*
X50631Y1589938D01*
G01X30000Y1586299D02*
X50631Y1589938D01*
G01X51180Y1588613D02*
X30123Y1584899D01*
G01X28429Y1586299D02*
X30000D01*
G01X30123Y1584899D02*
X28429D01*
G01X30782Y1636693D02*
X28429D01*
G01X31223Y1635293D02*
X28429D01*
G01X32050Y1637580D02*
X30782Y1636693D01*
G01X33055Y1636573D02*
X31223Y1635293D01*
G01X42757Y1652885D02*
X32051Y1637581D01*
G01X44083Y1652336D02*
X33055Y1636573D01*
G01X31223Y1635293D02*
X28429D01*
G01X30782Y1636693D02*
X28429D01*
G01X33055Y1636573D02*
X31223Y1635293D01*
G01X32050Y1637580D02*
X30782Y1636693D01*
G01X44083Y1652336D02*
X33055Y1636573D01*
G01X42757Y1652885D02*
X32051Y1637581D01*
G01X30706Y1720523D02*
X28429D01*
G01X33644Y1721041D02*
X30706Y1720523D01*
G01X36920Y1723335D02*
X33644Y1721041D01*
G01X31018Y1699876D02*
X28429D01*
G01X31141Y1698476D02*
X28429D01*
G01X33718Y1700352D02*
X31018Y1699876D01*
G01X34267Y1699027D02*
X31141Y1698476D01*
G01X36057Y1701989D02*
X33718Y1700352D01*
G01X39400Y1702620D02*
X34267Y1699027D01*
G01X38124Y1703437D02*
X36057Y1701989D01*
G01X39400Y1702620D02*
X34267Y1699027D01*
G01X38394Y1703626D02*
X38124Y1703437D01*
G01X39400Y1702620D02*
X34267Y1699027D01*
G01X40521Y1706660D02*
X38394Y1703626D01*
G01X31141Y1698476D02*
X28429D01*
G01X31018Y1699876D02*
X28429D01*
G01X34267Y1699027D02*
X31141Y1698476D01*
G01X33718Y1700352D02*
X31018Y1699876D01*
G01X39400Y1702620D02*
X34267Y1699027D01*
G01X36057Y1701989D02*
X33718Y1700352D01*
G01X38124Y1703437D02*
X36057Y1701989D01*
G01X38394Y1703626D02*
X38124Y1703437D01*
G01X40521Y1706660D02*
X38394Y1703626D01*
G01X34381Y1687859D02*
X39470Y1691422D01*
G01X34930Y1686534D02*
X40476Y1690416D01*
G01X30645Y1687200D02*
X34381Y1687859D01*
G01X30768Y1685800D02*
X34930Y1686534D01*
G01X28506Y1687200D02*
X30645D01*
G01X28352Y1685800D02*
X30768D01*
G01X34930Y1686534D02*
X40476Y1690416D01*
G01X34381Y1687859D02*
X39470Y1691422D01*
G01X30768Y1685800D02*
X34930Y1686534D01*
G01X30645Y1687200D02*
X34381Y1687859D01*
G01X28352Y1685800D02*
X30768D01*
G01X28506Y1687200D02*
X30645D01*
G01X37823Y1675306D02*
X41087Y1677593D01*
G01X38372Y1673981D02*
X42093Y1676588D01*
G01X34273Y1674679D02*
X37823Y1675306D01*
G01X34396Y1673279D02*
X38372Y1673981D01*
G01X28429Y1674679D02*
X34273D01*
G01X28429Y1673279D02*
X34396D01*
G01X38372Y1673981D02*
X42093Y1676588D01*
G01X37823Y1675306D02*
X41087Y1677593D01*
G01X34396Y1673279D02*
X38372Y1673981D01*
G01X34273Y1674679D02*
X37823Y1675306D01*
G01X28429Y1673279D02*
X34396D01*
G01X28429Y1674679D02*
X34273D01*
G01X30706Y1720523D02*
X28429D01*
G01X33644Y1721041D02*
X30706Y1720523D01*
G01X36920Y1723335D02*
X33644Y1721041D01*
G01X31209Y1758318D02*
X28429D01*
G01X31083Y1759718D02*
X28429D01*
G01X31595Y1758386D02*
X31209Y1758318D01*
G01X31083Y1759718D02*
X28429D01*
G01X31621Y1759813D02*
X31083Y1759718D01*
G01X32168Y1758487D02*
X31595Y1758386D01*
G01X31621Y1759813D02*
X31083Y1759718D01*
G01X33439Y1759375D02*
X32168Y1758487D01*
G01X31621Y1759813D02*
X31083Y1759718D01*
G01X32433Y1760381D02*
X31621Y1759813D01*
G01X35315Y1762056D02*
X33439Y1759375D01*
G01X33990Y1762605D02*
X32433Y1760381D01*
G01X51733Y1855121D02*
X35315Y1762056D01*
G01X50408Y1855670D02*
X33990Y1762605D01*
G01X31083Y1759718D02*
X28429D01*
G01X31209Y1758318D02*
X28429D01*
G01X31595Y1758386D02*
X31209Y1758318D01*
G01X31621Y1759813D02*
X31083Y1759718D01*
G01X31595Y1758386D02*
X31209Y1758318D01*
G01X32168Y1758487D02*
X31595Y1758386D01*
G01X33439Y1759375D02*
X32168Y1758487D01*
G01X32433Y1760381D02*
X31621Y1759813D01*
G01X33439Y1759375D02*
X32168Y1758487D01*
G01X33990Y1762605D02*
X32433Y1760381D01*
G01X35315Y1762056D02*
X33439Y1759375D01*
G01X50408Y1855670D02*
X33990Y1762605D01*
G01X51733Y1855121D02*
X35315Y1762056D01*
G01X31206Y1745720D02*
X28429D01*
G01X31083Y1747120D02*
X28429D01*
G01X32187Y1745893D02*
X31206Y1745720D01*
G01X31638Y1747218D02*
X31083Y1747120D01*
G01X35301Y1748072D02*
X32187Y1745893D01*
G01X31638Y1747218D02*
X31083Y1747120D01*
G01X34295Y1749078D02*
X31638Y1747218D01*
G01X37179Y1750756D02*
X35301Y1748072D01*
G01X35854Y1751305D02*
X34295Y1749078D01*
G01X55339Y1853704D02*
X37179Y1750756D01*
G01X54014Y1854253D02*
X35854Y1751305D01*
G01X31083Y1747120D02*
X28429D01*
G01X31206Y1745720D02*
X28429D01*
G01X31638Y1747218D02*
X31083Y1747120D01*
G01X32187Y1745893D02*
X31206Y1745720D01*
G01X35301Y1748072D02*
X32187Y1745893D01*
G01X34295Y1749078D02*
X31638Y1747218D01*
G01X35301Y1748072D02*
X32187Y1745893D01*
G01X35854Y1751305D02*
X34295Y1749078D01*
G01X37179Y1750756D02*
X35301Y1748072D01*
G01X54014Y1854253D02*
X35854Y1751305D01*
G01X55339Y1853704D02*
X37179Y1750756D01*
G01X31207Y1733121D02*
X28429D01*
G01X31084Y1734521D02*
X28429D01*
G01X31633Y1733196D02*
X31207Y1733121D01*
G01X31084Y1734521D02*
X28429D01*
G01X34823Y1735428D02*
X31633Y1733196D01*
G01X33817Y1736434D02*
X31084Y1734521D01*
G01X39281Y1741795D02*
X34823Y1735428D01*
G01X37956Y1742344D02*
X33817Y1736434D01*
G01X57462Y1852964D02*
X37956Y1742344D01*
G01X31084Y1734521D02*
X28429D01*
G01X31207Y1733121D02*
X28429D01*
G01X31633Y1733196D02*
X31207Y1733121D01*
G01X33817Y1736434D02*
X31084Y1734521D01*
G01X34823Y1735428D02*
X31633Y1733196D01*
G01X37956Y1742344D02*
X33817Y1736434D01*
G01X39281Y1741795D02*
X34823Y1735428D01*
G01X57462Y1852964D02*
X37956Y1742344D01*
G01X30583Y1721923D02*
X28429D01*
G01X33095Y1722366D02*
X30583Y1721923D01*
G01X35914Y1724341D02*
X33095Y1722366D01*
G01X39343Y1729237D02*
X35916Y1724342D01*
G01X40668Y1728688D02*
X36920Y1723335D01*
G01X30583Y1721923D02*
X28429D01*
G01X33095Y1722366D02*
X30583Y1721923D01*
G01X35914Y1724341D02*
X33095Y1722366D01*
G01X40668Y1728688D02*
X36920Y1723335D01*
G01X39343Y1729237D02*
X35916Y1724342D01*
G01X110178Y64692D02*
X114086Y65381D01*
G01X113537Y66706D02*
X110055Y66092D01*
G01X105899Y64692D02*
X110178D01*
G01X110055Y66092D02*
X105901D01*
G01X110055D02*
X105901D01*
G01X105899Y64692D02*
X110178D01*
G01X113537Y66706D02*
X110055Y66092D01*
G01X110178Y64692D02*
X114086Y65381D01*
G01X110564Y83590D02*
X114057Y84206D01*
G01X110441Y84990D02*
X113661Y85558D01*
G01X105899Y83590D02*
X110564D01*
G01X105901Y84990D02*
X110441D01*
G01D02*
X113661Y85558D01*
G01X110564Y83590D02*
X114057Y84206D01*
G01X105901Y84990D02*
X110441D01*
G01X105899Y83590D02*
X110564D01*
G01Y102488D02*
X116970Y103617D01*
G01X110441Y103888D02*
X116421Y104942D01*
G01X105900Y102488D02*
X110564D01*
G01X105900Y103888D02*
X110441D01*
G01D02*
X116421Y104942D01*
G01X110564Y102488D02*
X116970Y103617D01*
G01X105900Y103888D02*
X110441D01*
G01X105900Y102488D02*
X110564D01*
G01Y152881D02*
X105899D01*
G01X110441Y154281D02*
X105901D01*
G01X113110Y153330D02*
X110564Y152881D01*
G01X112561Y154655D02*
X110441Y154281D01*
G01X105143Y228377D02*
X116947Y161440D01*
G01X110441Y154281D02*
X105901D01*
G01X110564Y152881D02*
X105899D01*
G01X112561Y154655D02*
X110441Y154281D01*
G01X113110Y153330D02*
X110564Y152881D01*
G01X105143Y228377D02*
X116947Y161440D01*
G01X112911Y256104D02*
X65086Y324400D01*
G01X111586Y255555D02*
X63761Y323851D01*
G01X111586Y255555D02*
X63761Y323851D01*
G01X112911Y256104D02*
X65086Y324400D01*
G01X107602Y256075D02*
X46314Y343583D01*
G01X106277Y255526D02*
X44989Y343034D01*
G01X130470Y126434D02*
X107602Y256075D01*
G01X129048Y126435D02*
X106277Y255526D01*
G01D02*
X44989Y343034D01*
G01X107602Y256075D02*
X46314Y343583D01*
G01X129048Y126435D02*
X106277Y255526D01*
G01X130470Y126434D02*
X107602Y256075D01*
G01X106522Y228620D02*
X118326Y161682D01*
G01X102083Y253795D02*
X106522Y228620D01*
G01X100758Y253246D02*
X105143Y228377D01*
G01X106522Y228620D02*
X118326Y161682D01*
G01X100758Y253246D02*
X105143Y228377D01*
G01X102083Y253795D02*
X106522Y228620D01*
G01X110568Y311499D02*
X90567Y340064D01*
G01X109655Y310362D02*
X89242Y339515D01*
G01X118845Y308064D02*
X110568Y311499D01*
G01X118450Y306712D02*
X109655Y310362D01*
G01D02*
X89242Y339515D01*
G01X110568Y311499D02*
X90567Y340064D01*
G01X118450Y306712D02*
X109655Y310362D01*
G01X118845Y308064D02*
X110568Y311499D01*
G01X88096Y333445D02*
X114413Y295862D01*
G01X113407Y294856D02*
X86771Y332895D01*
G01X83986Y356751D02*
X88096Y333445D01*
G01X86771Y332895D02*
X82564Y356751D01*
G01X86771Y332895D02*
X82564Y356751D01*
G01X83986D02*
X88096Y333445D01*
G01X113407Y294856D02*
X86771Y332895D01*
G01X88096Y333445D02*
X114413Y295862D01*
G01X81783Y335066D02*
X126087Y271790D01*
G01X125081Y270784D02*
X80458Y334517D01*
G01X78957Y351091D02*
X81783Y335066D01*
G01X80458Y334517D02*
X77535Y351091D01*
G01X80458Y334517D02*
X77535Y351091D01*
G01X78957D02*
X81783Y335066D01*
G01X125081Y270784D02*
X80458Y334517D01*
G01X81783Y335066D02*
X126087Y271790D01*
G01X78482Y333312D02*
X120258Y273648D01*
G01X77157Y332763D02*
X118933Y273099D01*
G01X75336Y351150D02*
X78482Y333312D01*
G01X73914Y351150D02*
X77157Y332763D01*
G01D02*
X118933Y273099D01*
G01X78482Y333312D02*
X120258Y273648D01*
G01X73914Y351150D02*
X77157Y332763D01*
G01X75336Y351150D02*
X78482Y333312D01*
G01X73473Y322902D02*
X47764Y468824D01*
G01X46342D02*
X72148Y322353D01*
G01X115815Y262437D02*
X73473Y322902D01*
G01X72148Y322353D02*
X114490Y261888D01*
G01X72148Y322353D02*
X114490Y261888D01*
G01X115815Y262437D02*
X73473Y322902D01*
G01X46342Y468824D02*
X72148Y322353D01*
G01X73473Y322902D02*
X47764Y468824D01*
G01X65086Y324400D02*
X41631Y457417D01*
G01X63761Y323851D02*
X40209Y457417D01*
G01X63761Y323851D02*
X40209Y457417D01*
G01X65086Y324400D02*
X41631Y457417D01*
G01X97520Y375702D02*
X157025Y386195D01*
G01X96971Y377027D02*
X156476Y387520D01*
G01X94698Y373726D02*
X97520Y375702D01*
G01X93692Y374732D02*
X96971Y377027D01*
G01X90804Y368163D02*
X94698Y373726D01*
G01X89479Y368712D02*
X93692Y374732D01*
G01X88208Y353449D02*
X90804Y368163D01*
G01X86786Y353449D02*
X89479Y368712D01*
G01X90567Y340064D02*
X88208Y353449D01*
G01X89242Y339515D02*
X86786Y353449D01*
G01X96971Y377027D02*
X156476Y387520D01*
G01X97520Y375702D02*
X157025Y386195D01*
G01X93692Y374732D02*
X96971Y377027D01*
G01X94698Y373726D02*
X97520Y375702D01*
G01X89479Y368712D02*
X93692Y374732D01*
G01X90804Y368163D02*
X94698Y373726D01*
G01X86786Y353449D02*
X89479Y368712D01*
G01X88208Y353449D02*
X90804Y368163D01*
G01X89242Y339515D02*
X86786Y353449D01*
G01X90567Y340064D02*
X88208Y353449D01*
G01X85910Y367659D02*
X83986Y356751D01*
G01X82564D02*
X84585Y368208D01*
G01X91825Y376106D02*
X85910Y367659D01*
G01X84585Y368208D02*
X90819Y377112D01*
G01X100015Y381844D02*
X91825Y376106D01*
G01X90819Y377112D02*
X99466Y383169D01*
G01X158924Y392229D02*
X100015Y381844D01*
G01X99466Y383169D02*
X158375Y393554D01*
G01X99466Y383169D02*
X158375Y393554D01*
G01X158924Y392229D02*
X100015Y381844D01*
G01X90819Y377112D02*
X99466Y383169D01*
G01X100015Y381844D02*
X91825Y376106D01*
G01X84585Y368208D02*
X90819Y377112D01*
G01X91825Y376106D02*
X85910Y367659D01*
G01X82564Y356751D02*
X84585Y368208D01*
G01X85910Y367659D02*
X83986Y356751D01*
G01X81982Y368247D02*
X78957Y351091D01*
G01X77535D02*
X80656Y368795D01*
G01X82141Y368474D02*
X81982Y368247D01*
G01X81002Y369289D02*
X88494Y379988D01*
G01X80656Y368795D02*
X80993Y369278D01*
G01X82149Y368485D02*
X82141Y368474D01*
G01X81002Y369289D02*
X88494Y379988D01*
G01X89500Y378982D02*
X82149Y368485D01*
G01X81002Y369289D02*
X88494Y379988D01*
G01X80656Y368795D02*
X80993Y369278D01*
G01X98898Y385560D02*
X89500Y378982D01*
G01X88494Y379988D02*
X98349Y386885D01*
G01X157378Y395884D02*
X98898Y385560D01*
G01X98349Y386885D02*
X156829Y397209D01*
G01X98349Y386885D02*
X156829Y397209D01*
G01X157378Y395884D02*
X98898Y385560D01*
G01X88494Y379988D02*
X98349Y386885D01*
G01X98898Y385560D02*
X89500Y378982D01*
G01X81002Y369289D02*
X88494Y379988D01*
G01X82141Y368474D02*
X81982Y368247D01*
G01X82149Y368485D02*
X82141Y368474D01*
G01X89500Y378982D02*
X82149Y368485D01*
G01X80656Y368795D02*
X80993Y369278D01*
G01X82141Y368474D02*
X81982Y368247D01*
G01X89500Y378982D02*
X82149Y368485D01*
G01X77535Y351091D02*
X80656Y368795D01*
G01X81982Y368247D02*
X78957Y351091D01*
G01X78748Y370489D02*
X75336Y351150D01*
G01X77423Y371038D02*
X73914Y351150D01*
G01X88498Y384413D02*
X78748Y370489D01*
G01X87492Y385419D02*
X77423Y371038D01*
G01X94359Y388517D02*
X88498Y384413D01*
G01X93810Y389842D02*
X87492Y385419D01*
G01X156196Y399421D02*
X94359Y388517D01*
G01X155647Y400746D02*
X93810Y389842D01*
G01X77423Y371038D02*
X73914Y351150D01*
G01X78748Y370489D02*
X75336Y351150D01*
G01X87492Y385419D02*
X77423Y371038D01*
G01X88498Y384413D02*
X78748Y370489D01*
G01X93810Y389842D02*
X87492Y385419D01*
G01X94359Y388517D02*
X88498Y384413D01*
G01X155647Y400746D02*
X93810Y389842D01*
G01X156196Y399421D02*
X94359Y388517D01*
G01X110178Y470204D02*
X105899D01*
G01X110055Y471604D02*
X105901D01*
G01X114198Y470912D02*
X110178Y470204D01*
G01X113801Y472264D02*
X110055Y471604D01*
G01X47764Y468824D02*
X62795Y554179D01*
G01X61373D02*
X46342Y468824D01*
G01X61373Y554179D02*
X46342Y468824D01*
G01X47764D02*
X62795Y554179D01*
G01X110055Y471604D02*
X105901D01*
G01X110178Y470204D02*
X105899D01*
G01X113801Y472264D02*
X110055Y471604D01*
G01X114198Y470912D02*
X110178Y470204D01*
G01X41631Y457417D02*
X58760Y554540D01*
G01X40209Y457417D02*
X57338Y554540D01*
G01X40209Y457417D02*
X57338Y554540D01*
G01X41631Y457417D02*
X58760Y554540D01*
G01X62795Y554179D02*
X50681Y622880D01*
G01X49355Y622335D02*
X61373Y554179D01*
G01X49355Y622335D02*
X61373Y554179D01*
G01X62795D02*
X50681Y622880D01*
G01X110564Y489102D02*
X114298Y489760D01*
G01X110441Y490502D02*
X113751Y491086D01*
G01X105899Y489102D02*
X110564D01*
G01X105901Y490502D02*
X110441D01*
G01D02*
X113751Y491086D01*
G01X110564Y489102D02*
X114298Y489760D01*
G01X105901Y490502D02*
X110441D01*
G01X105899Y489102D02*
X110564D01*
G01Y508000D02*
X112291Y508304D01*
G01X110441Y509400D02*
X111742Y509629D01*
G01X105900Y508000D02*
X110564D01*
G01X105900Y509400D02*
X110441D01*
G01D02*
X111742Y509629D01*
G01X110564Y508000D02*
X112291Y508304D01*
G01X105900Y509400D02*
X110441D01*
G01X105900Y508000D02*
X110564D01*
G01X58760Y554540D02*
X48332Y613670D01*
G01X57338Y554540D02*
X47007Y613121D01*
G01X57338Y554540D02*
X47007Y613121D01*
G01X58760Y554540D02*
X48332Y613670D01*
G01X54965Y553465D02*
X46781Y599892D01*
G01X53543Y553465D02*
X52453Y559647D01*
G01X54965Y553465D02*
X46781Y599892D01*
G01X54965Y553465D02*
X46781Y599892D01*
G01X53543Y553465D02*
X52453Y559647D01*
G01X54965Y553465D02*
X46781Y599892D01*
G01X40737Y595331D02*
X49658Y544721D01*
G01X46254Y555960D02*
X48236Y544721D01*
G01X46254Y555960D02*
X48236Y544721D01*
G01X40737Y595331D02*
X49658Y544721D01*
G01X40737Y595331D02*
X49658Y544721D01*
G01X40737Y595331D02*
X49658Y544721D01*
G01X40737Y595331D02*
X49658Y544721D01*
G01X40737Y595331D02*
X49658Y544721D01*
G01X40737Y595331D02*
X49658Y544721D01*
G01X100932Y669969D02*
X114616Y592376D01*
G01X99607Y669420D02*
X113291Y591827D01*
G01X50683Y622880D02*
X41525Y635961D01*
G01X43605Y630548D02*
X49355Y622335D01*
G01X43605Y630548D02*
X49355Y622335D01*
G01X50683Y622880D02*
X41525Y635961D01*
G01X50683Y622880D02*
X41525Y635961D01*
G01X99607Y669420D02*
X113291Y591827D01*
G01X100932Y669969D02*
X114616Y592376D01*
G01X111785Y586178D02*
X98411Y662002D01*
G01X110482Y585500D02*
X97085Y661453D01*
G01X110482Y585500D02*
X97085Y661453D01*
G01X121803Y569327D02*
X110482Y585500D01*
G01D02*
X97085Y661453D01*
G01X111785Y586178D02*
X98411Y662002D01*
G01X121803Y569327D02*
X110482Y585500D01*
G01X108218Y584135D02*
X95718Y654991D01*
G01X106893Y583586D02*
X94334Y654774D01*
G01X116810Y571865D02*
X108218Y584135D01*
G01X115485Y571316D02*
X106893Y583586D01*
G01X108218Y584135D02*
X95718Y654991D01*
G01X106893Y583586D02*
X94334Y654774D01*
G01X108218Y584135D02*
X95718Y654991D01*
G01X115485Y571316D02*
X106893Y583586D01*
G01X116810Y571865D02*
X108218Y584135D01*
G01X105324Y579721D02*
X93229Y648260D01*
G01X94708Y631819D02*
X103999Y579172D01*
G01X113066Y568662D02*
X105324Y579721D01*
G01X110170Y570357D02*
X111741Y568113D01*
G01X107084Y574765D02*
X108203Y573167D01*
G01X103999Y579172D02*
X105117Y577575D01*
G01X111548Y561864D02*
X110731Y560695D01*
G01X111548Y561864D02*
X110731Y560695D01*
G01X110311Y558691D02*
X111736Y559688D01*
G01X110731Y560695D02*
X109762Y560016D01*
G01X108623Y558393D02*
X110311Y558691D01*
G01X109762Y560016D02*
X108500Y559793D01*
G01X105899Y558393D02*
X108623D01*
G01X108500Y559793D02*
X105901D01*
G01X108500D02*
X105901D01*
G01X105899Y558393D02*
X108623D01*
G01X109762Y560016D02*
X108500Y559793D01*
G01X108623Y558393D02*
X110311Y558691D01*
G01X110731Y560695D02*
X109762Y560016D01*
G01X110311Y558691D02*
X111736Y559688D01*
G01X111548Y561864D02*
X110731Y560695D01*
G01X110170Y570357D02*
X111741Y568113D01*
G01X113066Y568662D02*
X105324Y579721D01*
G01X107084Y574765D02*
X108203Y573167D01*
G01X113066Y568662D02*
X105324Y579721D01*
G01X103999Y579172D02*
X105117Y577575D01*
G01X113066Y568662D02*
X105324Y579721D01*
G01X94708Y631819D02*
X103999Y579172D01*
G01X105324Y579721D02*
X93229Y648260D01*
G01X105324Y579721D02*
X93229Y648260D01*
G01X105324Y579721D02*
X93229Y648260D01*
G01X105324Y579721D02*
X93229Y648260D01*
G01X43465Y618179D02*
X39167Y621187D01*
G01X48332Y613670D02*
X44471Y619185D01*
G01X47007Y613121D02*
X43465Y618179D01*
G01D02*
X39167Y621187D01*
G01X47007Y613121D02*
X43465Y618179D01*
G01X48332Y613670D02*
X44471Y619185D01*
G01X40093Y607001D02*
X38974Y608598D01*
G01X45456Y599343D02*
X42060Y604191D01*
G01X50924Y568323D02*
X45456Y599343D01*
G01X51858Y563025D02*
X51519Y564945D01*
G01X40093Y607001D02*
X38974Y608598D01*
G01X45456Y599343D02*
X42060Y604191D01*
G01X50924Y568323D02*
X45456Y599343D01*
G01X51858Y563025D02*
X51519Y564945D01*
G01X45320Y561258D02*
X45659Y559338D01*
G01X44386Y566556D02*
X44725Y564636D01*
G01X41961Y580312D02*
X43791Y569934D01*
G01X41028Y585611D02*
X41367Y583690D01*
G01X39412Y594782D02*
X40433Y588989D01*
G01X45320Y561258D02*
X45659Y559338D01*
G01X44386Y566556D02*
X44725Y564636D01*
G01X41961Y580312D02*
X43791Y569934D01*
G01X41028Y585611D02*
X41367Y583690D01*
G01X39412Y594782D02*
X40433Y588989D01*
G01X124886Y675338D02*
X46015Y787986D01*
G01X123561Y674789D02*
X45009Y786980D01*
G01X123561Y674789D02*
X45009Y786980D01*
G01X124886Y675338D02*
X46015Y787986D01*
G01X116117Y677386D02*
X58585Y759573D01*
G01X114792Y676837D02*
X57578Y758570D01*
G01X114792Y676837D02*
X57578Y758570D01*
G01X116117Y677386D02*
X58585Y759573D01*
G01X98079Y674043D02*
X100932Y669969D01*
G01X97073Y673037D02*
X99607Y669420D01*
G01X62979Y698620D02*
X98079Y674043D01*
G01X95476Y674156D02*
X97073Y673037D01*
G01X94445Y673974D02*
X95476Y674156D01*
G01X91069Y677241D02*
X92666Y676123D01*
G01X90038Y677060D02*
X91069Y677241D01*
G01X88258Y679209D02*
X88259D01*
G01X71859Y690692D02*
X88258Y679209D01*
G01X70829Y690510D02*
X71859Y690692D01*
G01X67453Y693778D02*
X69050Y692659D01*
G01X66423Y693596D02*
X67453Y693778D01*
G01X62430Y697295D02*
X64644Y695745D01*
G01X58474Y697992D02*
X62430Y697295D01*
G01X53176Y698925D02*
X55096Y698587D01*
G01X124554Y599874D02*
X111351Y674763D01*
G01X67031Y740502D02*
X112676Y675312D01*
G01X111351Y674763D02*
X66025Y739496D01*
G01X111351Y674763D02*
X66025Y739496D01*
G01X67031Y740502D02*
X112676Y675312D01*
G01X124554Y599874D02*
X111351Y674763D01*
G01X109148Y673709D02*
X122344Y598859D01*
G01X121019Y598310D02*
X107823Y673160D01*
G01X84474Y708928D02*
X109148Y673709D01*
G01X107823Y673160D02*
X83468Y707921D01*
G01X107823Y673160D02*
X83468Y707921D01*
G01X84474Y708928D02*
X109148Y673709D01*
G01X121019Y598310D02*
X107823Y673160D01*
G01X109148Y673709D02*
X122344Y598859D01*
G01X105511Y672051D02*
X118665Y597445D01*
G01X104186Y671502D02*
X117340Y596896D01*
G01X94663Y687545D02*
X105511Y672051D01*
G01X93657Y686539D02*
X104186Y671502D01*
G01X60102Y711744D02*
X94663Y687545D01*
G01X59553Y710419D02*
X93657Y686539D01*
G01X104186Y671502D02*
X117340Y596896D01*
G01X105511Y672051D02*
X118665Y597445D01*
G01X93657Y686539D02*
X104186Y671502D01*
G01X94663Y687545D02*
X105511Y672051D01*
G01X59553Y710419D02*
X93657Y686539D01*
G01X60102Y711744D02*
X94663Y687545D01*
G01X40519Y634955D02*
X41637Y633358D01*
G01X40519Y634955D02*
X41637Y633358D01*
G01X97073Y673037D02*
X99607Y669420D01*
G01X98079Y674043D02*
X100932Y669969D01*
G01X95476Y674156D02*
X97073Y673037D01*
G01X62979Y698620D02*
X98079Y674043D01*
G01X94445Y673974D02*
X95476Y674156D01*
G01X62979Y698620D02*
X98079Y674043D01*
G01X91069Y677241D02*
X92666Y676123D01*
G01X62979Y698620D02*
X98079Y674043D01*
G01X90038Y677060D02*
X91069Y677241D01*
G01X62979Y698620D02*
X98079Y674043D01*
G01X88258Y679209D02*
X88259D01*
G01X62979Y698620D02*
X98079Y674043D01*
G01X71859Y690692D02*
X88258Y679209D01*
G01X62979Y698620D02*
X98079Y674043D01*
G01X70829Y690510D02*
X71859Y690692D01*
G01X62979Y698620D02*
X98079Y674043D01*
G01X67453Y693778D02*
X69050Y692659D01*
G01X62979Y698620D02*
X98079Y674043D01*
G01X66423Y693596D02*
X67453Y693778D01*
G01X62979Y698620D02*
X98079Y674043D01*
G01X62430Y697295D02*
X64644Y695745D01*
G01X62979Y698620D02*
X98079Y674043D01*
G01X58474Y697992D02*
X62430Y697295D01*
G01X53176Y698925D02*
X55096Y698587D01*
G01X41384Y688402D02*
X39463Y688741D01*
G01X70818Y683208D02*
X44761Y687806D01*
G01X93472Y669058D02*
X71367Y684533D01*
G01X72415Y682090D02*
X70818Y683208D01*
G01X75225Y680122D02*
X74195Y679941D01*
G01X76823Y679004D02*
X75225Y680122D01*
G01X79633Y677037D02*
X78602Y676855D01*
G01X81230Y675919D02*
X79633Y677037D01*
G01X84040Y673951D02*
X83009Y673770D01*
G01X92466Y668052D02*
X84040Y673951D01*
G01X98411Y662002D02*
X93472Y669058D01*
G01X97085Y661454D02*
X92466Y668052D01*
G01X41384Y688402D02*
X39463Y688741D01*
G01X70818Y683208D02*
X44761Y687806D01*
G01X72415Y682090D02*
X70818Y683208D01*
G01X93472Y669058D02*
X71367Y684533D01*
G01X75225Y680122D02*
X74195Y679941D01*
G01X93472Y669058D02*
X71367Y684533D01*
G01X76823Y679004D02*
X75225Y680122D01*
G01X93472Y669058D02*
X71367Y684533D01*
G01X79633Y677037D02*
X78602Y676855D01*
G01X93472Y669058D02*
X71367Y684533D01*
G01X81230Y675919D02*
X79633Y677037D01*
G01X93472Y669058D02*
X71367Y684533D01*
G01X84040Y673951D02*
X83009Y673770D01*
G01X93472Y669058D02*
X71367Y684533D01*
G01X92466Y668052D02*
X84040Y673951D01*
G01X93472Y669058D02*
X71367Y684533D01*
G01X97085Y661454D02*
X92466Y668052D01*
G01X98411Y662002D02*
X93472Y669058D01*
G01X41382Y675806D02*
X39462Y676145D01*
G01X64456Y671739D02*
X44760Y675211D01*
G01X69754Y670805D02*
X67834Y671143D01*
G01X78098Y669334D02*
X73132Y670209D01*
G01X91006Y662006D02*
X78647Y670659D01*
G01X90000Y661000D02*
X78098Y669334D01*
G01X95634Y655398D02*
X91006Y662006D01*
G01X94327Y654822D02*
X90000Y661000D01*
G01X94335Y654776D02*
X94331Y654799D01*
G01X41382Y675806D02*
X39462Y676145D01*
G01X64456Y671739D02*
X44760Y675211D01*
G01X69754Y670805D02*
X67834Y671143D01*
G01X78098Y669334D02*
X73132Y670209D01*
G01X90000Y661000D02*
X78098Y669334D01*
G01X91006Y662006D02*
X78647Y670659D01*
G01X94327Y654822D02*
X90000Y661000D01*
G01X95634Y655398D02*
X91006Y662006D01*
G01X94335Y654776D02*
X94331Y654799D01*
G01X70662Y660621D02*
X80529Y658881D01*
G01X65364Y661555D02*
X67284Y661216D01*
G01X88506Y655006D02*
X81078Y660206D01*
G01X80529Y658881D02*
X87500Y654000D01*
G01X93229Y648260D02*
X88506Y655006D01*
G01X87500Y654000D02*
X91902Y647714D01*
G01X93772Y637118D02*
X94111Y635198D01*
G01X92837Y642416D02*
X93176Y640496D01*
G01X91902Y647714D02*
X92241Y645794D01*
G01X93772Y637118D02*
X94111Y635198D01*
G01X92837Y642416D02*
X93176Y640496D01*
G01X91902Y647714D02*
X92241Y645794D01*
G01X87500Y654000D02*
X91902Y647714D01*
G01X93229Y648260D02*
X88506Y655006D01*
G01X80529Y658881D02*
X87500Y654000D01*
G01X88506Y655006D02*
X81078Y660206D01*
G01X70662Y660621D02*
X80529Y658881D01*
G01X65364Y661555D02*
X67284Y661216D01*
G01X107754Y720881D02*
X117915Y713764D01*
G01X117366Y712439D02*
X106748Y719875D01*
G01X94967Y739141D02*
X107754Y720881D01*
G01X106748Y719875D02*
X93819Y738337D01*
G01X47961Y806263D02*
X94967Y739141D01*
G01X93819Y738337D02*
X46636Y805714D01*
G01X93819Y738337D02*
X46636Y805714D01*
G01X47961Y806263D02*
X94967Y739141D01*
G01X106748Y719875D02*
X93819Y738337D01*
G01X94967Y739141D02*
X107754Y720881D01*
G01X117366Y712439D02*
X106748Y719875D01*
G01X107754Y720881D02*
X117915Y713764D01*
G01X42350Y807070D02*
X118718Y698008D01*
G01X117712Y697002D02*
X41025Y806521D01*
G01X117712Y697002D02*
X41025Y806521D01*
G01X42350Y807070D02*
X118718Y698008D01*
G01X58581Y759578D02*
X41156Y771778D01*
G01X57578Y758570D02*
X40607Y770453D01*
G01X57578Y758570D02*
X40607Y770453D01*
G01X58581Y759578D02*
X41156Y771778D01*
G01X40086Y759368D02*
X67031Y740502D01*
G01X66025Y739496D02*
X39537Y758043D01*
G01X66025Y739496D02*
X39537Y758043D01*
G01X40086Y759368D02*
X67031Y740502D01*
G01X63249Y723789D02*
X84474Y708928D01*
G01X83469Y707921D02*
X62700Y722464D01*
G01X83468Y707921D02*
X83469D01*
G01D02*
X62700Y722464D01*
G01X63249Y723789D02*
X84474Y708928D01*
G01X83468Y707921D02*
X83469D01*
G01X63249Y723789D02*
X84474Y708928D01*
G01X100550Y794651D02*
X146237Y802717D01*
G01X146786Y801392D02*
X100550Y793229D01*
G01X80704Y798152D02*
X100550Y794651D01*
G01Y793229D02*
X80155Y796827D01*
G01X77969Y800068D02*
X80704Y798152D01*
G01X80155Y796827D02*
X76963Y799062D01*
G01X64314Y819574D02*
X77969Y800068D01*
G01X76963Y799062D02*
X62989Y819025D01*
G01X56261Y865284D02*
X64314Y819574D01*
G01X62989Y819025D02*
X54933Y864752D01*
G01X62989Y819025D02*
X54933Y864752D01*
G01X56261Y865284D02*
X64314Y819574D01*
G01X76963Y799062D02*
X62989Y819025D01*
G01X64314Y819574D02*
X77969Y800068D01*
G01X80155Y796827D02*
X76963Y799062D01*
G01X77969Y800068D02*
X80704Y798152D01*
G01X100550Y793229D02*
X80155Y796827D01*
G01X80704Y798152D02*
X100550Y794651D01*
G01X146786Y801392D02*
X100550Y793229D01*
G01Y794651D02*
X146237Y802717D01*
G01X100990Y791045D02*
X151724Y800013D01*
G01X101113Y789645D02*
X152273Y798688D01*
G01X100551Y791045D02*
X100990D01*
G01X101113Y789645D02*
X152273Y798688D01*
G01X100428Y789645D02*
X101113D01*
G01X78765Y793465D02*
X100428Y789645D01*
G01X79314Y794790D02*
X100551Y791045D01*
G01X78765Y793465D02*
X100428Y789645D01*
G01X74061Y798469D02*
X79314Y794790D01*
G01X73055Y797463D02*
X78765Y793465D01*
G01X58959Y820046D02*
X74061Y798469D01*
G01X57642Y819483D02*
X73055Y797463D01*
G01X52927Y854259D02*
X58959Y820046D01*
G01X51602Y853710D02*
X57633Y819498D01*
G01X101113Y789645D02*
X152273Y798688D01*
G01X100990Y791045D02*
X151724Y800013D01*
G01X100551Y791045D02*
X100990D01*
G01X100428Y789645D02*
X101113D01*
G01X100551Y791045D02*
X100990D01*
G01X78765Y793465D02*
X100428Y789645D01*
G01X100551Y791045D02*
X100990D01*
G01X79314Y794790D02*
X100551Y791045D01*
G01X73055Y797463D02*
X78765Y793465D01*
G01X74061Y798469D02*
X79314Y794790D01*
G01X57642Y819483D02*
X73055Y797463D01*
G01X58959Y820046D02*
X74061Y798469D01*
G01X51602Y853710D02*
X57633Y819498D01*
G01X52927Y854259D02*
X58959Y820046D01*
G01X51644Y838966D02*
X41081Y854052D01*
G01X50319Y838417D02*
X40282Y852751D01*
G01X56067Y813887D02*
X51644Y838966D01*
G01X54742Y813338D02*
X50319Y838417D01*
G01X57186Y812290D02*
X56067Y813887D01*
G01X69178Y792721D02*
X54742Y813338D01*
G01X60272Y807883D02*
X59153Y809480D01*
G01X69178Y792721D02*
X54742Y813338D01*
G01X70184Y793727D02*
X62239Y805073D01*
G01X69178Y792721D02*
X54742Y813338D01*
G01X76940Y788998D02*
X70184Y793727D01*
G01X76391Y787673D02*
X69178Y792721D01*
G01X78860Y788660D02*
X76940Y788998D01*
G01X94096Y784555D02*
X76391Y787673D01*
G01X84159Y787727D02*
X82238Y788065D01*
G01X94096Y784555D02*
X76391Y787673D01*
G01X94096Y785977D02*
X87537Y787132D01*
G01X94096Y784555D02*
X76391Y787673D01*
G01X153604Y796470D02*
X94096Y785977D01*
G01X154153Y795145D02*
X94096Y784555D01*
G01X51644Y838966D02*
X41081Y854052D01*
G01X50319Y838417D02*
X40282Y852751D01*
G01X51644Y838966D02*
X41081Y854052D01*
G01X54742Y813338D02*
X50319Y838417D01*
G01X56067Y813887D02*
X51644Y838966D01*
G01X69178Y792721D02*
X54742Y813338D01*
G01X57186Y812290D02*
X56067Y813887D01*
G01X60272Y807883D02*
X59153Y809480D01*
G01X70184Y793727D02*
X62239Y805073D01*
G01X76391Y787673D02*
X69178Y792721D01*
G01X76940Y788998D02*
X70184Y793727D01*
G01X94096Y784555D02*
X76391Y787673D01*
G01X78860Y788660D02*
X76940Y788998D01*
G01X84159Y787727D02*
X82238Y788065D01*
G01X94096Y785977D02*
X87537Y787132D01*
G01X154153Y795145D02*
X94096Y784555D01*
G01X153604Y796470D02*
X94096Y785977D01*
G01X45668Y819276D02*
X47961Y806263D01*
G01X46636Y805714D02*
X44343Y818727D01*
G01X46636Y805714D02*
X44343Y818727D01*
G01X45668Y819276D02*
X47961Y806263D01*
G01X41497Y811913D02*
X42350Y807070D01*
G01X41025Y806521D02*
X40172Y811364D01*
G01X41025Y806521D02*
X40172Y811364D01*
G01X41497Y811913D02*
X42350Y807070D01*
G01X89365Y781498D02*
X155350Y793127D01*
G01X89365Y780076D02*
X155899Y791802D01*
G01X87445Y781837D02*
X89365Y781498D01*
G01X77977Y782085D02*
X89365Y780076D01*
G01X78526Y783410D02*
X84067Y782433D01*
G01X77977Y782085D02*
X89365Y780076D01*
G01X67282Y791283D02*
X78526Y783410D01*
G01X66276Y790277D02*
X77977Y782085D01*
G01X52190Y812835D02*
X67282Y791283D01*
G01X50865Y812286D02*
X66276Y790277D01*
G01X49290Y829288D02*
X52190Y812835D01*
G01X47965Y828739D02*
X50865Y812286D01*
G01X45390Y834857D02*
X49290Y829288D01*
G01X40692Y839124D02*
X47965Y828739D01*
G01X41696Y840132D02*
X43423Y837667D01*
G01X40692Y839124D02*
X47965Y828739D01*
G01X89365Y780076D02*
X155899Y791802D01*
G01X89365Y781498D02*
X155350Y793127D01*
G01X77977Y782085D02*
X89365Y780076D01*
G01X87445Y781837D02*
X89365Y781498D01*
G01X78526Y783410D02*
X84067Y782433D01*
G01X66276Y790277D02*
X77977Y782085D01*
G01X67282Y791283D02*
X78526Y783410D01*
G01X50865Y812286D02*
X66276Y790277D01*
G01X52190Y812835D02*
X67282Y791283D01*
G01X47965Y828739D02*
X50865Y812286D01*
G01X49290Y829288D02*
X52190Y812835D01*
G01X40692Y839124D02*
X47965Y828739D01*
G01X45390Y834857D02*
X49290Y829288D01*
G01X41696Y840132D02*
X43423Y837667D01*
G01X110384Y875716D02*
X105899D01*
G01X105901Y877116D02*
X110507D01*
G01X115959Y874733D02*
X110384Y875716D01*
G01X110507Y877116D02*
X116508Y876058D01*
G01X51065Y873077D02*
X56261Y865284D01*
G01X54933Y864752D02*
X49900Y872300D01*
G01X50397Y873683D02*
X50921Y873283D01*
G01X49900Y872300D02*
X49376Y872689D01*
G01X50382Y873694D02*
X50397Y873683D01*
G01X49900Y872300D02*
X49376Y872689D01*
G01X49900Y872300D02*
X49376Y872689D01*
G01X49900Y872300D02*
X49376Y872689D01*
G01X50397Y873683D02*
X50921Y873283D01*
G01X50382Y873694D02*
X50397Y873683D01*
G01X54933Y864752D02*
X49900Y872300D01*
G01X51065Y873077D02*
X56261Y865284D01*
G01X110507Y877116D02*
X116508Y876058D01*
G01X115959Y874733D02*
X110384Y875716D01*
G01X105901Y877116D02*
X110507D01*
G01X110384Y875716D02*
X105899D01*
G01X110441Y894614D02*
X105899D01*
G01X110883Y896014D02*
X105901D01*
G01X112038Y893496D02*
X110441Y894614D01*
G01X137460Y877406D02*
X110883Y896014D01*
G01X137460Y877406D02*
X110883Y896014D01*
G01X137460Y877406D02*
X110883Y896014D01*
G01X137460Y877406D02*
X110883Y896014D01*
G01X137460Y877406D02*
X110883Y896014D01*
G01X45739Y864530D02*
X52927Y854259D01*
G01X44733Y863524D02*
X51602Y853710D01*
G01X39875Y868635D02*
X45739Y864530D01*
G01X39196Y867400D02*
X44733Y863524D01*
G01X110883Y896014D02*
X105901D01*
G01X110441Y894614D02*
X105899D01*
G01X137460Y877406D02*
X110883Y896014D01*
G01X112038Y893496D02*
X110441Y894614D01*
G01X44733Y863524D02*
X51602Y853710D01*
G01X45739Y864530D02*
X52927Y854259D01*
G01X39196Y867400D02*
X44733Y863524D01*
G01X39875Y868635D02*
X45739Y864530D01*
G01X40282Y852751D02*
X40075Y853047D01*
G01X110442Y913512D02*
X119516Y907158D01*
G01X110884Y914912D02*
X120522Y908164D01*
G01X105900Y913512D02*
X110442D01*
G01X105900Y914912D02*
X110884D01*
G01X40282Y852751D02*
X40075Y853047D01*
G01X110884Y914912D02*
X120522Y908164D01*
G01X110442Y913512D02*
X119516Y907158D01*
G01X105900Y914912D02*
X110884D01*
G01X105900Y913512D02*
X110442D01*
G01X80293Y1008895D02*
X118203Y982352D01*
G01X79745Y1007569D02*
X117197Y981346D01*
G01X45795Y924954D02*
X59179Y1000865D01*
G01X47120Y924405D02*
X60504Y1000316D01*
G01X79745Y1007569D02*
X117197Y981346D01*
G01X80293Y1008895D02*
X118203Y982352D01*
G01X80293Y1008895D02*
X118203Y982352D01*
G01X47120Y924405D02*
X60504Y1000316D01*
G01X45795Y924954D02*
X59179Y1000865D01*
G01X103828Y981903D02*
X116170Y973895D01*
G01X103283Y980587D02*
X115179Y972869D01*
G01X96079Y983550D02*
X103828Y981903D01*
G01X96079Y982118D02*
X103283Y980587D01*
G01X85610Y981323D02*
X96079Y983550D01*
G01X82543Y979238D02*
X96079Y982118D01*
G01X81998Y980554D02*
X85610Y981323D01*
G01X82543Y979238D02*
X96079Y982118D01*
G01X67319Y971022D02*
X81998Y980554D01*
G01X68332Y970009D02*
X82543Y979238D01*
G01X60932Y961188D02*
X67319Y971022D01*
G01X62262Y960664D02*
X68332Y970009D01*
G01X54886Y926897D02*
X60932Y961188D01*
G01X56211Y926348D02*
X62262Y960664D01*
G01X103283Y980587D02*
X115179Y972869D01*
G01X103828Y981903D02*
X116170Y973895D01*
G01X96079Y982118D02*
X103283Y980587D01*
G01X96079Y983550D02*
X103828Y981903D01*
G01X82543Y979238D02*
X96079Y982118D01*
G01X85610Y981323D02*
X96079Y983550D01*
G01X81998Y980554D02*
X85610Y981323D01*
G01X68332Y970009D02*
X82543Y979238D01*
G01X67319Y971022D02*
X81998Y980554D01*
G01X62262Y960664D02*
X68332Y970009D01*
G01X60932Y961188D02*
X67319Y971022D01*
G01X56211Y926348D02*
X62262Y960664D01*
G01X54886Y926897D02*
X60932Y961188D01*
G01X109500Y963905D02*
X105899D01*
G01X109623Y965305D02*
X105901D01*
G01X111509Y963551D02*
X109500Y963905D01*
G01X112058Y964876D02*
X109623Y965305D01*
G01X113284Y962308D02*
X111509Y963551D01*
G01X109623Y965305D02*
X105901D01*
G01X109500Y963905D02*
X105899D01*
G01X112058Y964876D02*
X109623Y965305D01*
G01X111509Y963551D02*
X109500Y963905D01*
G01X113284Y962308D02*
X111509Y963551D01*
G01X108455Y1079102D02*
X120395Y1011387D01*
G01X108455Y1079102D02*
X120395Y1011387D01*
G01X106357Y1077378D02*
X118208Y1010166D01*
G01X105032Y1076829D02*
X116883Y1009617D01*
G01X105032Y1076829D02*
X116883Y1009617D01*
G01X106357Y1077378D02*
X118208Y1010166D01*
G01X104719Y1014677D02*
X95470Y1067131D01*
G01X103394Y1014128D02*
X94145Y1066582D01*
G01X130692Y977587D02*
X104719Y1014677D01*
G01X129367Y977038D02*
X103394Y1014128D01*
G01D02*
X94145Y1066582D01*
G01X104719Y1014677D02*
X95470Y1067131D01*
G01X129367Y977038D02*
X103394Y1014128D01*
G01X130692Y977587D02*
X104719Y1014677D01*
G01X92467Y1062626D02*
X85799Y1072147D01*
G01X91142Y1062077D02*
X84793Y1071141D01*
G01X101254Y1012800D02*
X92467Y1062626D01*
G01X99929Y1012251D02*
X91142Y1062077D01*
G01X126832Y976273D02*
X101254Y1012800D01*
G01X125589Y975606D02*
X99929Y1012251D01*
G01X91142Y1062077D02*
X84793Y1071141D01*
G01X92467Y1062626D02*
X85799Y1072147D01*
G01X99929Y1012251D02*
X91142Y1062077D01*
G01X101254Y1012800D02*
X92467Y1062626D01*
G01X125589Y975606D02*
X99929Y1012251D01*
G01X126832Y976273D02*
X101254Y1012800D01*
G01X114644Y1008847D02*
X104019Y1069130D01*
G01X113319Y1008298D02*
X102694Y1068581D01*
G01X113319Y1008298D02*
X102694Y1068581D01*
G01X114644Y1008847D02*
X104019Y1069130D01*
G01X79744Y1007569D02*
X79745D01*
G01X75186Y1009790D02*
X80293Y1008895D01*
G01X79744Y1007569D02*
X79745D01*
G01X75064Y1008390D02*
X79744Y1007569D01*
G01X71502Y1009790D02*
X75186D01*
G01X71625Y1008390D02*
X75064D01*
G01X66124Y1008840D02*
X71502Y1009790D01*
G01X66673Y1007515D02*
X71625Y1008390D01*
G01X63559Y1007045D02*
X66124Y1008840D01*
G01X64462Y1005968D02*
X66673Y1007515D01*
G01X59179Y1000865D02*
X63384Y1006870D01*
G01X60504Y1000316D02*
X64461Y1005967D01*
G01X79744Y1007569D02*
X79745D01*
G01X75186Y1009790D02*
X80293Y1008895D01*
G01X75064Y1008390D02*
X79744Y1007569D01*
G01X75186Y1009790D02*
X80293Y1008895D01*
G01X71625Y1008390D02*
X75064D01*
G01X71502Y1009790D02*
X75186D01*
G01X66673Y1007515D02*
X71625Y1008390D01*
G01X66124Y1008840D02*
X71502Y1009790D01*
G01X64462Y1005968D02*
X66673Y1007515D01*
G01X63559Y1007045D02*
X66124Y1008840D01*
G01X60504Y1000316D02*
X64461Y1005967D01*
G01X59179Y1000865D02*
X63384Y1006870D01*
G01X100150Y1135007D02*
X39241Y1221992D01*
G01X124202Y1118166D02*
X100150Y1135007D01*
G01X123653Y1116841D02*
X99144Y1134001D01*
G01X100150Y1135007D02*
X39241Y1221992D01*
G01X123653Y1116841D02*
X99144Y1134001D01*
G01X124202Y1118166D02*
X100150Y1135007D01*
G01X61447Y1156255D02*
X113182Y1082367D01*
G01X60441Y1155249D02*
X111857Y1081818D01*
G01X60441Y1155249D02*
X111857Y1081818D01*
G01X61447Y1156255D02*
X113182Y1082367D01*
G01X114242Y1105231D02*
X44372Y1205015D01*
G01X115248Y1106237D02*
X45518Y1205820D01*
G01X114242Y1105231D02*
X44372Y1205015D01*
G01X114242Y1105231D02*
X44372Y1205015D01*
G01X115248Y1106237D02*
X45518Y1205820D01*
G01X109780Y1079651D02*
X121720Y1011936D01*
G01X57080Y1154917D02*
X109780Y1079651D01*
G01X56074Y1153911D02*
X108455Y1079102D01*
G01X109780Y1079651D02*
X121720Y1011936D01*
G01X56074Y1153911D02*
X108455Y1079102D01*
G01X57080Y1154917D02*
X109780Y1079651D01*
G01X125273Y1083286D02*
X52826Y1186718D01*
G01X124267Y1082280D02*
X51820Y1185712D01*
G01X124267Y1082280D02*
X51820Y1185712D01*
G01X125273Y1083286D02*
X52826Y1186718D01*
G01X59117Y1144846D02*
X106357Y1077378D01*
G01X58111Y1143840D02*
X105032Y1076829D01*
G01X58111Y1143840D02*
X105032Y1076829D01*
G01X59117Y1144846D02*
X106357Y1077378D01*
G01X117187Y1086237D02*
X54646Y1175557D01*
G01X115862Y1085688D02*
X53640Y1174551D01*
G01X115862Y1085688D02*
X53640Y1174551D01*
G01X117187Y1086237D02*
X54646Y1175557D01*
G01X80860Y1087997D02*
X51571Y1108504D01*
G01X79854Y1086991D02*
X51022Y1107179D01*
G01X95470Y1067131D02*
X80860Y1087997D01*
G01X94145Y1066582D02*
X79854Y1086991D01*
G01D02*
X51022Y1107179D01*
G01X80860Y1087997D02*
X51571Y1108504D01*
G01X94145Y1066582D02*
X79854Y1086991D01*
G01X95470Y1067131D02*
X80860Y1087997D01*
G01X85799Y1072147D02*
X51961Y1095836D01*
G01X84793Y1071141D02*
X51412Y1094511D01*
G01X84793Y1071141D02*
X51412Y1094511D01*
G01X85799Y1072147D02*
X51961Y1095836D01*
G01X73478Y1112743D02*
X40806Y1135619D01*
G01X72472Y1111737D02*
X40257Y1134294D01*
G01X104019Y1069130D02*
X73478Y1112743D01*
G01X102694Y1068581D02*
X72472Y1111737D01*
G01D02*
X40257Y1134294D01*
G01X73478Y1112743D02*
X40806Y1135619D01*
G01X102694Y1068581D02*
X72472Y1111737D01*
G01X104019Y1069130D02*
X73478Y1112743D01*
G01X90471Y1197416D02*
X153007Y1208440D01*
G01X90471Y1195994D02*
X153007Y1207018D01*
G01X83505Y1198645D02*
X90471Y1197416D01*
G01X82956Y1197320D02*
X90471Y1195994D01*
G01X68995Y1208804D02*
X83505Y1198645D01*
G01X67989Y1207798D02*
X82956Y1197320D01*
G01X64772Y1214834D02*
X68995Y1208804D01*
G01X63447Y1214285D02*
X67989Y1207798D01*
G01X90471Y1195994D02*
X153007Y1207018D01*
G01X90471Y1197416D02*
X153007Y1208440D01*
G01X82956Y1197320D02*
X90471Y1195994D01*
G01X83505Y1198645D02*
X90471Y1197416D01*
G01X67989Y1207798D02*
X82956Y1197320D01*
G01X68995Y1208804D02*
X83505Y1198645D01*
G01X63447Y1214285D02*
X67989Y1207798D01*
G01X64772Y1214834D02*
X68995Y1208804D01*
G01X65925Y1206556D02*
X61407Y1213006D01*
G01X64919Y1205550D02*
X60082Y1212457D01*
G01X81992Y1195305D02*
X65925Y1206556D01*
G01X81443Y1193980D02*
X64919Y1205550D01*
G01X91512Y1193627D02*
X81992Y1195305D01*
G01X91512Y1192205D02*
X81443Y1193980D01*
G01X153956Y1204635D02*
X91512Y1193627D01*
G01X153956Y1203213D02*
X91512Y1192205D01*
G01X64919Y1205550D02*
X60082Y1212457D01*
G01X65925Y1206556D02*
X61407Y1213006D01*
G01X81443Y1193980D02*
X64919Y1205550D01*
G01X81992Y1195305D02*
X65925Y1206556D01*
G01X91512Y1192205D02*
X81443Y1193980D01*
G01X91512Y1193627D02*
X81992Y1195305D01*
G01X153956Y1203213D02*
X91512Y1192205D01*
G01X153956Y1204635D02*
X91512Y1193627D01*
G01X56429Y1211369D02*
X49795Y1248997D01*
G01X63263Y1204054D02*
X57754Y1211918D01*
G01X62257Y1203048D02*
X56429Y1211369D01*
G01X80800Y1191774D02*
X63263Y1204054D01*
G01X80252Y1190448D02*
X62257Y1203048D01*
G01X91244Y1189931D02*
X80800Y1191774D01*
G01X91244Y1188509D02*
X80252Y1190448D01*
G01X153975Y1200992D02*
X91244Y1189931D01*
G01X153975Y1199570D02*
X91244Y1188509D01*
G01X56429Y1211369D02*
X49795Y1248997D01*
G01X62257Y1203048D02*
X56429Y1211369D01*
G01X63263Y1204054D02*
X57754Y1211918D01*
G01X80252Y1190448D02*
X62257Y1203048D01*
G01X80800Y1191774D02*
X63263Y1204054D01*
G01X91244Y1188509D02*
X80252Y1190448D01*
G01X91244Y1189931D02*
X80800Y1191774D01*
G01X153975Y1199570D02*
X91244Y1188509D01*
G01X153975Y1200992D02*
X91244Y1189931D01*
G01X90849Y1186145D02*
X153929Y1197268D01*
G01Y1195846D02*
X90849Y1184723D01*
G01X79887Y1188077D02*
X90849Y1186145D01*
G01Y1184723D02*
X79338Y1186752D01*
G01X60170Y1201884D02*
X79887Y1188077D01*
G01X79338Y1186752D02*
X59164Y1200878D01*
G01X53955Y1210760D02*
X60170Y1201884D01*
G01X59164Y1200878D02*
X52630Y1210211D01*
G01X48767Y1240190D02*
X53955Y1210760D01*
G01X52630Y1210211D02*
X47442Y1239641D01*
G01X52630Y1210211D02*
X47442Y1239641D01*
G01X48767Y1240190D02*
X53955Y1210760D01*
G01X59164Y1200878D02*
X52630Y1210211D01*
G01X53955Y1210760D02*
X60170Y1201884D01*
G01X79338Y1186752D02*
X59164Y1200878D01*
G01X60170Y1201884D02*
X79887Y1188077D01*
G01X90849Y1184723D02*
X79338Y1186752D01*
G01X79887Y1188077D02*
X90849Y1186145D01*
G01X153929Y1195846D02*
X90849Y1184723D01*
G01Y1186145D02*
X153929Y1197268D01*
G01X45518Y1205820D02*
X45375Y1206024D01*
G01X45518Y1205820D02*
X45375Y1206024D01*
G01X46766Y1162138D02*
X57080Y1154917D01*
G01X46217Y1160813D02*
X56074Y1153911D01*
G01X46217Y1160813D02*
X56074Y1153911D01*
G01X46766Y1162138D02*
X57080Y1154917D01*
G01X50588Y1150821D02*
X59117Y1144846D01*
G01X50018Y1149510D02*
X58111Y1143840D01*
G01X42332Y1152575D02*
X50588Y1150821D01*
G01X42332Y1151143D02*
X50018Y1149510D01*
G01D02*
X58111Y1143840D01*
G01X50588Y1150821D02*
X59117Y1144846D01*
G01X42332Y1151143D02*
X50018Y1149510D01*
G01X42332Y1152575D02*
X50588Y1150821D01*
G01X43442Y1183401D02*
X39347Y1186269D01*
G01X54646Y1175557D02*
X43442Y1183401D01*
G01X53640Y1174551D02*
X42764Y1182166D01*
G01X43442Y1183401D02*
X39347Y1186269D01*
G01X53640Y1174551D02*
X42764Y1182166D01*
G01X54646Y1175557D02*
X43442Y1183401D01*
G01X54840Y1271160D02*
X64772Y1214834D01*
G01X53515Y1270611D02*
X63447Y1214285D01*
G01X47764Y1281265D02*
X54840Y1271160D01*
G01X46617Y1280462D02*
X53515Y1270611D01*
G01X43911Y1286768D02*
X47764Y1281265D01*
G01X42905Y1285762D02*
X46617Y1280462D01*
G01X53515Y1270611D02*
X63447Y1214285D01*
G01X54840Y1271160D02*
X64772Y1214834D01*
G01X46617Y1280462D02*
X53515Y1270611D01*
G01X47764Y1281265D02*
X54840Y1271160D01*
G01X42905Y1285762D02*
X46617Y1280462D01*
G01X43911Y1286768D02*
X47764Y1281265D01*
G01X109509Y1281228D02*
X105899D01*
G01X109728Y1282628D02*
X105901D01*
G01X115549Y1282175D02*
X109700Y1281167D01*
G01X115002Y1283502D02*
X109800Y1282605D01*
G01X109728Y1282628D02*
X105901D01*
G01X109509Y1281228D02*
X105899D01*
G01X115002Y1283502D02*
X109800Y1282605D01*
G01X115549Y1282175D02*
X109700Y1281167D01*
G01X42550Y1274128D02*
X42547Y1274130D01*
G01X52761Y1261985D02*
X43555Y1275135D01*
G01X51436Y1261436D02*
X42552Y1274125D01*
G01X61407Y1213006D02*
X52761Y1261985D01*
G01X60082Y1212457D02*
X51436Y1261436D01*
G01X42550Y1274128D02*
X42547Y1274130D01*
G01X51436Y1261436D02*
X42552Y1274125D01*
G01X52761Y1261985D02*
X43555Y1275135D01*
G01X60082Y1212457D02*
X51436Y1261436D01*
G01X61407Y1213006D02*
X52761Y1261985D01*
G01X51120Y1249546D02*
X41322Y1263538D01*
G01X49795Y1248997D02*
X40315Y1262533D01*
G01X57754Y1211918D02*
X51120Y1249546D01*
G01X49795Y1248997D02*
X40315Y1262533D01*
G01X51120Y1249546D02*
X41322Y1263538D01*
G01X57754Y1211918D02*
X51120Y1249546D01*
G01X41112Y1251125D02*
X48767Y1240190D01*
G01X47442Y1239641D02*
X40106Y1250119D01*
G01X47442Y1239641D02*
X40106Y1250119D01*
G01X41112Y1251125D02*
X48767Y1240190D01*
G01X113663Y1300126D02*
X105899D01*
G01X105901Y1301526D02*
X113786D01*
G01X42252Y1348780D02*
X41134Y1347183D01*
G01X45338Y1353187D02*
X44220Y1351590D01*
G01X64003Y1379848D02*
X47305Y1355997D01*
G01X42252Y1348780D02*
X41134Y1347183D01*
G01X45338Y1353187D02*
X44220Y1351590D01*
G01X64003Y1379848D02*
X47305Y1355997D01*
G01X105901Y1301526D02*
X113786D01*
G01X113663Y1300126D02*
X105899D01*
G01X43906Y1333694D02*
X39178Y1330384D01*
G01X47323Y1341016D02*
X42900Y1334700D01*
G01X47364Y1338633D02*
X43906Y1333694D01*
G01X48470Y1340213D02*
X47364Y1338633D01*
G01X48648Y1340467D02*
X48470Y1340212D01*
G01X49479Y1353244D02*
X47323Y1341016D01*
G01X50804Y1352694D02*
X48648Y1340467D01*
G01X62684Y1372105D02*
X49479Y1353244D01*
G01X51922Y1354292D02*
X50804Y1352695D01*
G01X55008Y1358699D02*
X53890Y1357102D01*
G01X111477Y1348735D02*
X111816Y1350655D01*
G01X110174Y1341342D02*
X110882Y1345357D01*
G01X112163Y1330060D02*
X110174Y1341342D01*
G01X111337Y1319454D02*
X112985Y1320608D01*
G01X110788Y1320779D02*
X111979Y1321614D01*
G01X108900Y1319024D02*
X111337Y1319454D01*
G01X108777Y1320424D02*
X110788Y1320779D01*
G01X105900Y1319024D02*
X108900D01*
G01X105900Y1320424D02*
X108777D01*
G01X43906Y1333694D02*
X39178Y1330384D01*
G01X47364Y1338633D02*
X43906Y1333694D01*
G01X47323Y1341016D02*
X42900Y1334700D01*
G01X48470Y1340213D02*
X47364Y1338633D01*
G01X47323Y1341016D02*
X42900Y1334700D01*
G01X48648Y1340467D02*
X48470Y1340212D01*
G01X47323Y1341016D02*
X42900Y1334700D01*
G01X50804Y1352694D02*
X48648Y1340467D01*
G01X49479Y1353244D02*
X47323Y1341016D01*
G01X51922Y1354292D02*
X50804Y1352695D01*
G01X62684Y1372105D02*
X49479Y1353244D01*
G01X55008Y1358699D02*
X53890Y1357102D01*
G01X62684Y1372105D02*
X49479Y1353244D01*
G01X62684Y1372105D02*
X49479Y1353244D01*
G01X62684Y1372105D02*
X49479Y1353244D01*
G01X111477Y1348735D02*
X111816Y1350655D01*
G01X110174Y1341342D02*
X110882Y1345357D01*
G01X112163Y1330060D02*
X110174Y1341342D01*
G01X110788Y1320779D02*
X111979Y1321614D01*
G01X111337Y1319454D02*
X112985Y1320608D01*
G01X108777Y1320424D02*
X110788Y1320779D01*
G01X108900Y1319024D02*
X111337Y1319454D01*
G01X105900Y1320424D02*
X108777D01*
G01X105900Y1319024D02*
X108900D01*
G01X41999Y1320847D02*
X40402Y1319729D01*
G01X43030Y1320665D02*
X41999Y1320847D01*
G01X50730Y1326960D02*
X44809Y1322815D01*
G01X60380Y1343184D02*
X49724Y1327966D01*
G01X51848Y1328557D02*
X50730Y1326960D01*
G01X54934Y1332965D02*
X53816Y1331367D01*
G01X61705Y1342635D02*
X56901Y1335774D01*
G01X64255Y1365152D02*
X60380Y1343184D01*
G01X62244Y1345689D02*
X61705Y1342635D01*
G01X63179Y1350987D02*
X62840Y1349067D01*
G01X64113Y1356285D02*
X63774Y1354365D01*
G01X41999Y1320847D02*
X40402Y1319729D01*
G01X43030Y1320665D02*
X41999Y1320847D01*
G01X50730Y1326960D02*
X44809Y1322815D01*
G01X51848Y1328557D02*
X50730Y1326960D01*
G01X60380Y1343184D02*
X49724Y1327966D01*
G01X54934Y1332965D02*
X53816Y1331367D01*
G01X60380Y1343184D02*
X49724Y1327966D01*
G01X61705Y1342635D02*
X56901Y1335774D01*
G01X60380Y1343184D02*
X49724Y1327966D01*
G01X62244Y1345689D02*
X61705Y1342635D01*
G01X64255Y1365152D02*
X60380Y1343184D01*
G01X63179Y1350987D02*
X62840Y1349067D01*
G01X64255Y1365152D02*
X60380Y1343184D01*
G01X64113Y1356285D02*
X63774Y1354365D01*
G01X64255Y1365152D02*
X60380Y1343184D01*
G01X64255Y1365152D02*
X60380Y1343184D01*
G01X45357Y1415603D02*
X58343Y1489276D01*
G01X46682Y1415054D02*
X59668Y1488727D01*
G01X41785Y1410502D02*
X45357Y1415603D01*
G01X42791Y1409496D02*
X46682Y1415054D01*
G01D02*
X59668Y1488727D01*
G01X45357Y1415603D02*
X58343Y1489276D01*
G01X42791Y1409496D02*
X46682Y1415054D01*
G01X41785Y1410502D02*
X45357Y1415603D01*
G01X47871Y1407952D02*
X62019Y1488080D01*
G01X49196Y1407403D02*
X63344Y1487531D01*
G01X40529Y1397466D02*
X47871Y1407952D01*
G01X41535Y1396460D02*
X49196Y1407403D01*
G01D02*
X63344Y1487531D01*
G01X47871Y1407952D02*
X62019Y1488080D01*
G01X41535Y1396460D02*
X49196Y1407403D01*
G01X40529Y1397466D02*
X47871Y1407952D01*
G01X50126Y1398415D02*
X40339Y1384438D01*
G01X51451Y1397866D02*
X41345Y1383432D01*
G01X65700Y1486761D02*
X50126Y1398415D01*
G01X67025Y1486212D02*
X51451Y1397866D01*
G01D02*
X41345Y1383432D01*
G01X50126Y1398415D02*
X40339Y1384438D01*
G01X67025Y1486212D02*
X51451Y1397866D01*
G01X65700Y1486761D02*
X50126Y1398415D01*
G01X54308Y1396630D02*
X44744Y1382972D01*
G01X56095Y1406771D02*
X54308Y1396630D01*
G01X55633Y1396081D02*
X57420Y1406222D01*
G01X63156Y1416856D02*
X56095Y1406771D01*
G01X57420Y1406222D02*
X64162Y1415850D01*
G01X71730Y1422857D02*
X63156Y1416856D01*
G01X64162Y1415850D02*
X72279Y1421532D01*
G01X133408Y1433733D02*
X71730Y1422857D01*
G01X72279Y1421532D02*
X133531Y1432333D01*
G01X72279Y1421532D02*
X133531Y1432333D01*
G01X133408Y1433733D02*
X71730Y1422857D01*
G01X64162Y1415850D02*
X72279Y1421532D01*
G01X71730Y1422857D02*
X63156Y1416856D01*
G01X57420Y1406222D02*
X64162Y1415850D01*
G01X63156Y1416856D02*
X56095Y1406771D01*
G01X55633Y1396081D02*
X57420Y1406222D01*
G01X56095Y1406771D02*
X54308Y1396630D01*
G01D02*
X44744Y1382972D01*
G01X86142Y1412639D02*
X122037Y1387506D01*
G01X85593Y1411314D02*
X121031Y1386501D01*
G01X74011Y1414779D02*
X86142Y1412639D01*
G01X74011Y1413357D02*
X85593Y1411314D01*
G01X68126Y1413737D02*
X74011Y1414779D01*
G01X68675Y1412412D02*
X74011Y1413357D01*
G01X65675Y1412024D02*
X68126Y1413737D01*
G01X66681Y1411018D02*
X68675Y1412412D01*
G01X61317Y1405792D02*
X65675Y1412024D01*
G01X62643Y1405243D02*
X66681Y1411018D01*
G01X58069Y1387387D02*
X61317Y1405792D01*
G01X62304Y1403323D02*
X62643Y1405243D01*
G01X59348Y1386574D02*
X61707Y1399945D01*
G01X47885Y1370401D02*
X59075Y1386382D01*
G01X44799Y1365994D02*
X45917Y1367591D01*
G01X41713Y1361587D02*
X42831Y1363184D01*
G01X85593Y1411314D02*
X121031Y1386501D01*
G01X86142Y1412639D02*
X122037Y1387506D01*
G01X74011Y1413357D02*
X85593Y1411314D01*
G01X74011Y1414779D02*
X86142Y1412639D01*
G01X68675Y1412412D02*
X74011Y1413357D01*
G01X68126Y1413737D02*
X74011Y1414779D01*
G01X66681Y1411018D02*
X68675Y1412412D01*
G01X65675Y1412024D02*
X68126Y1413737D01*
G01X62643Y1405243D02*
X66681Y1411018D01*
G01X61317Y1405792D02*
X65675Y1412024D01*
G01X62304Y1403323D02*
X62643Y1405243D01*
G01X58069Y1387387D02*
X61317Y1405792D01*
G01X59348Y1386574D02*
X61707Y1399945D01*
G01X58069Y1387387D02*
X61317Y1405792D01*
G01X47885Y1370401D02*
X59075Y1386382D01*
G01X44799Y1365994D02*
X45917Y1367591D01*
G01X41713Y1361587D02*
X42831Y1363184D01*
G01X93197Y1402667D02*
X118827Y1384721D01*
G01X117823Y1383713D02*
X92648Y1401342D01*
G01X85510Y1404024D02*
X93197Y1402667D01*
G01X92648Y1401342D02*
X85510Y1402602D01*
G01X80027Y1403055D02*
X85510Y1404024D01*
G01Y1402602D02*
X80576Y1401730D01*
G01X73114Y1398213D02*
X80027Y1403055D01*
G01X80576Y1401730D02*
X74120Y1397207D01*
G01X63363Y1384282D02*
X73114Y1398213D01*
G01X69453Y1390540D02*
X64688Y1383733D01*
G01X74120Y1397207D02*
X71420Y1393350D01*
G01X62678Y1380397D02*
X63363Y1384282D01*
G01X64688Y1383733D02*
X64003Y1379848D01*
G01X64688Y1383733D02*
X64003Y1379848D01*
G01X62678Y1380397D02*
X63363Y1384282D01*
G01X69453Y1390540D02*
X64688Y1383733D01*
G01X63363Y1384282D02*
X73114Y1398213D01*
G01X74120Y1397207D02*
X71420Y1393350D01*
G01X63363Y1384282D02*
X73114Y1398213D01*
G01X80576Y1401730D02*
X74120Y1397207D01*
G01X73114Y1398213D02*
X80027Y1403055D01*
G01X85510Y1402602D02*
X80576Y1401730D01*
G01X80027Y1403055D02*
X85510Y1404024D01*
G01X92648Y1401342D02*
X85510Y1402602D01*
G01Y1404024D02*
X93197Y1402667D01*
G01X117823Y1383713D02*
X92648Y1401342D01*
G01X93197Y1402667D02*
X118827Y1384721D01*
G01X58094Y1363107D02*
X56976Y1361509D01*
G01X63690Y1371099D02*
X60061Y1365916D01*
G01X78840Y1383415D02*
X62684Y1372105D01*
G01X79846Y1382409D02*
X63690Y1371099D01*
G01X81000Y1386500D02*
X78840Y1383415D01*
G01X82006Y1385494D02*
X79846Y1382409D01*
G01X85777Y1389843D02*
X81000Y1386500D01*
G01X86326Y1388518D02*
X82006Y1385494D01*
G01X94971Y1391466D02*
X85777Y1389843D01*
G01X94971Y1390044D02*
X86326Y1388518D01*
G01X104850Y1389724D02*
X94971Y1391466D01*
G01X104301Y1388399D02*
X94971Y1390044D01*
G01X115526Y1382249D02*
X104850Y1389724D01*
G01X114521Y1381243D02*
X104301Y1388399D01*
G01X58094Y1363107D02*
X56976Y1361509D01*
G01X63690Y1371099D02*
X60061Y1365916D01*
G01X79846Y1382409D02*
X63690Y1371099D01*
G01X78840Y1383415D02*
X62684Y1372105D01*
G01X82006Y1385494D02*
X79846Y1382409D01*
G01X81000Y1386500D02*
X78840Y1383415D01*
G01X86326Y1388518D02*
X82006Y1385494D01*
G01X85777Y1389843D02*
X81000Y1386500D01*
G01X94971Y1390044D02*
X86326Y1388518D01*
G01X94971Y1391466D02*
X85777Y1389843D01*
G01X104301Y1388399D02*
X94971Y1390044D01*
G01X104850Y1389724D02*
X94971Y1391466D01*
G01X114521Y1381243D02*
X104301Y1388399D01*
G01X115526Y1382249D02*
X104850Y1389724D01*
G01X65580Y1364603D02*
X64709Y1359663D01*
G01X68000Y1370500D02*
X64255Y1365152D01*
G01X69006Y1369494D02*
X65580Y1364603D01*
G01X80702Y1379396D02*
X68000Y1370500D01*
G01X81505Y1378248D02*
X69006Y1369494D01*
G01X80948Y1379641D02*
G02X80702Y1379396I-818J575D01*
G01X82097Y1378838D02*
G02X81507Y1378249I-1965J1378D01*
G01X84000Y1384000D02*
X80948Y1379641D01*
G01X85006Y1382994D02*
X82097Y1378838D01*
G01X86583Y1385809D02*
X84000Y1384000D01*
G01X87132Y1384484D02*
X85006Y1382994D01*
G01X92169Y1386794D02*
X86583Y1385809D01*
G01X92169Y1385372D02*
X87132Y1384484D01*
G01X105466Y1384448D02*
X92169Y1386794D01*
G01X104917Y1383122D02*
X92169Y1385372D01*
G01X110080Y1381217D02*
X105466Y1384448D01*
G01X109074Y1380211D02*
X104917Y1383122D01*
G01X112862Y1377244D02*
X110080Y1381217D01*
G01X111537Y1376695D02*
X109076Y1380210D01*
G01X110869Y1371951D02*
X111551Y1372926D01*
G01X110050Y1369669D02*
X111875Y1370945D01*
G01X109501Y1370994D02*
X110869Y1371951D01*
G01X108500Y1370817D02*
X109501Y1370994D01*
G01X108623Y1369417D02*
X110050Y1369669D01*
G01X108500Y1370817D02*
X109501Y1370994D01*
G01X105899Y1369417D02*
X108623D01*
G01X105901Y1370817D02*
X108500D01*
G01X65580Y1364603D02*
X64709Y1359663D01*
G01X69006Y1369494D02*
X65580Y1364603D01*
G01X68000Y1370500D02*
X64255Y1365152D01*
G01X81505Y1378248D02*
X69006Y1369494D01*
G01X80702Y1379396D02*
X68000Y1370500D01*
G01X82097Y1378838D02*
G02X81507Y1378249I-1965J1378D01*
G01X80948Y1379641D02*
G02X80702Y1379396I-818J575D01*
G01X85006Y1382994D02*
X82097Y1378838D01*
G01X84000Y1384000D02*
X80948Y1379641D01*
G01X87132Y1384484D02*
X85006Y1382994D01*
G01X86583Y1385809D02*
X84000Y1384000D01*
G01X92169Y1385372D02*
X87132Y1384484D01*
G01X92169Y1386794D02*
X86583Y1385809D01*
G01X104917Y1383122D02*
X92169Y1385372D01*
G01X105466Y1384448D02*
X92169Y1386794D01*
G01X109074Y1380211D02*
X104917Y1383122D01*
G01X110080Y1381217D02*
X105466Y1384448D01*
G01X111537Y1376695D02*
X109076Y1380210D01*
G01X112862Y1377244D02*
X110080Y1381217D01*
G01X110869Y1371951D02*
X111551Y1372926D01*
G01X109501Y1370994D02*
X110869Y1371951D01*
G01X110050Y1369669D02*
X111875Y1370945D01*
G01X108500Y1370817D02*
X109501Y1370994D01*
G01X110050Y1369669D02*
X111875Y1370945D01*
G01X108623Y1369417D02*
X110050Y1369669D01*
G01X105901Y1370817D02*
X108500D01*
G01X105899Y1369417D02*
X108623D01*
G01X66466Y1500873D02*
X83941Y1513110D01*
G01X67472Y1499867D02*
X84490Y1511785D01*
G01X58343Y1489276D02*
X66466Y1500873D01*
G01X59668Y1488727D02*
X67472Y1499867D01*
G01D02*
X84490Y1511785D01*
G01X66466Y1500873D02*
X83941Y1513110D01*
G01X59668Y1488727D02*
X67472Y1499867D01*
G01X58343Y1489276D02*
X66466Y1500873D01*
G01X89949Y1505831D02*
X123739Y1499876D01*
G01X68770Y1497721D02*
X79835Y1505470D01*
G01X69776Y1496715D02*
X80384Y1504145D01*
G01X62019Y1488080D02*
X68770Y1497721D01*
G01X63344Y1487531D02*
X69776Y1496715D01*
G01X89949Y1505831D02*
X123739Y1499876D01*
G01X69776Y1496715D02*
X80384Y1504145D01*
G01X68770Y1497721D02*
X79835Y1505470D01*
G01X63344Y1487531D02*
X69776Y1496715D01*
G01X62019Y1488080D02*
X68770Y1497721D01*
G01X71173Y1494580D02*
X65700Y1486761D01*
G01X72179Y1493574D02*
X67025Y1486212D01*
G01X81252Y1501636D02*
X71173Y1494580D01*
G01X81801Y1500311D02*
X72179Y1493574D01*
G01X89697Y1503126D02*
X81252Y1501636D01*
G01X89697Y1501704D02*
X81801Y1500311D01*
G01X100006Y1501307D02*
X89697Y1503126D01*
G01X99457Y1499982D02*
X89697Y1501704D01*
G01X121436Y1486302D02*
X100006Y1501307D01*
G01X120886Y1484977D02*
X99457Y1499982D01*
G01X72179Y1493574D02*
X67025Y1486212D01*
G01X71173Y1494580D02*
X65700Y1486761D01*
G01X81801Y1500311D02*
X72179Y1493574D01*
G01X81252Y1501636D02*
X71173Y1494580D01*
G01X89697Y1501704D02*
X81801Y1500311D01*
G01X89697Y1503126D02*
X81252Y1501636D01*
G01X99457Y1499982D02*
X89697Y1501704D01*
G01X100006Y1501307D02*
X89697Y1503126D01*
G01X120886Y1484977D02*
X99457Y1499982D01*
G01X121436Y1486302D02*
X100006Y1501307D01*
G01X47765Y1558878D02*
X90208Y1588598D01*
G01X48771Y1557872D02*
X90757Y1587273D01*
G01X48771Y1557872D02*
X90757Y1587273D01*
G01X47765Y1558878D02*
X90208Y1588598D01*
G01X92546Y1585303D02*
X58042Y1561147D01*
G01X93095Y1583978D02*
X59048Y1560141D01*
G01X93095Y1583978D02*
X59048Y1560141D01*
G01X92546Y1585303D02*
X58042Y1561147D01*
G01X83941Y1513110D02*
X133917Y1521922D01*
G01X84490Y1511785D02*
X134040Y1520522D01*
G01X84490Y1511785D02*
X134040Y1520522D01*
G01X83941Y1513110D02*
X133917Y1521922D01*
G01X89949Y1507253D02*
X123739Y1501298D01*
G01X79835Y1505470D02*
X89949Y1507253D01*
G01X80384Y1504145D02*
X89949Y1505831D01*
G01Y1507253D02*
X123739Y1501298D01*
G01X80384Y1504145D02*
X89949Y1505831D01*
G01X79835Y1505470D02*
X89949Y1507253D01*
G01X82059Y1609865D02*
X151624Y1622132D01*
G01X82059Y1611287D02*
X151075Y1623457D01*
G01X46801Y1616089D02*
X82059Y1609865D01*
G01X47350Y1617414D02*
X82059Y1611287D01*
G01X39846Y1620958D02*
X46801Y1616089D01*
G01X40396Y1622283D02*
X47350Y1617414D01*
G01X82059Y1611287D02*
X151075Y1623457D01*
G01X82059Y1609865D02*
X151624Y1622132D01*
G01X47350Y1617414D02*
X82059Y1611287D01*
G01X46801Y1616089D02*
X82059Y1609865D01*
G01X40396Y1622283D02*
X47350Y1617414D01*
G01X39846Y1620958D02*
X46801Y1616089D01*
G01X81913Y1606212D02*
X159495Y1619886D01*
G01X158945Y1621211D02*
X81913Y1607634D01*
G01X44945Y1612730D02*
X81913Y1606212D01*
G01Y1607634D02*
X44945Y1614152D01*
G01X81913Y1607634D02*
X44945Y1614152D01*
G01Y1612730D02*
X81913Y1606212D01*
G01X158945Y1621211D02*
X81913Y1607634D01*
G01Y1606212D02*
X159495Y1619886D01*
G01X81998Y1602579D02*
X70475Y1604612D01*
G01X70476Y1606034D02*
X81998Y1604001D01*
G01X162369Y1616748D02*
X81998Y1602579D01*
G01Y1604001D02*
X161819Y1618073D01*
G01X81998Y1604001D02*
X161819Y1618073D01*
G01X162369Y1616748D02*
X81998Y1602579D01*
G01X70476Y1606034D02*
X81998Y1604001D01*
G01Y1602579D02*
X70475Y1604612D01*
G01X60460Y1595111D02*
X51180Y1588613D01*
G01X50631Y1589938D02*
X59911Y1596436D01*
G01X163949Y1613354D02*
X60460Y1595111D01*
G01X59911Y1596436D02*
X163399Y1614679D01*
G01X59911Y1596436D02*
X163399Y1614679D01*
G01X163949Y1613354D02*
X60460Y1595111D01*
G01X50631Y1589938D02*
X59911Y1596436D01*
G01X60460Y1595111D02*
X51180Y1588613D01*
G01X73724Y1593396D02*
X176436Y1611506D01*
G01X74273Y1592071D02*
X176679Y1610126D01*
G01X74273Y1592071D02*
X176679Y1610126D01*
G01X73724Y1593396D02*
X176436Y1611506D01*
G01X89348Y1592368D02*
X176509Y1607731D01*
G01X89897Y1591043D02*
X176752Y1606351D01*
G01X89897Y1591043D02*
X176752Y1606351D01*
G01X89348Y1592368D02*
X176509Y1607731D01*
G01X90208Y1588598D02*
X177204Y1603932D01*
G01X90757Y1587273D02*
X177447Y1602553D01*
G01X90757Y1587273D02*
X177447Y1602553D01*
G01X90208Y1588598D02*
X177204Y1603932D01*
G01X176757Y1600159D02*
X92546Y1585303D01*
G01X177000Y1598779D02*
X93095Y1583978D01*
G01X177000Y1598779D02*
X93095Y1583978D01*
G01X176757Y1600159D02*
X92546Y1585303D01*
G01X41846Y1706111D02*
X39400Y1702620D01*
G01X58534Y1808812D02*
X40521Y1706660D01*
G01X59859Y1808264D02*
X41846Y1706111D01*
G01D02*
X39400Y1702620D01*
G01X59859Y1808264D02*
X41846Y1706111D01*
G01X58534Y1808812D02*
X40521Y1706660D01*
G01X42249Y1695391D02*
X58214Y1785913D01*
G01X43574Y1694842D02*
X59539Y1785364D01*
G01X39470Y1691422D02*
X42249Y1695391D01*
G01X40476Y1690416D02*
X43574Y1694842D01*
G01D02*
X59539Y1785364D01*
G01X42249Y1695391D02*
X58214Y1785913D01*
G01X40476Y1690416D02*
X43574Y1694842D01*
G01X39470Y1691422D02*
X42249Y1695391D01*
G01X43794Y1681462D02*
X59500Y1770530D01*
G01X45119Y1680911D02*
X60825Y1769981D01*
G01X41087Y1677593D02*
X43793Y1681460D01*
G01X42093Y1676588D02*
X45119Y1680911D01*
G01D02*
X60825Y1769981D01*
G01X43794Y1681462D02*
X59500Y1770530D01*
G01X42093Y1676588D02*
X45119Y1680911D01*
G01X41087Y1677593D02*
X43793Y1681460D01*
G01X110180Y1688140D02*
X105901D01*
G01X110055Y1686740D02*
X105899D01*
G01X123661Y1685718D02*
X110180Y1688140D01*
G01X123413Y1684340D02*
X110055Y1686740D01*
G01D02*
X105899D01*
G01X110180Y1688140D02*
X105901D01*
G01X123413Y1684340D02*
X110055Y1686740D01*
G01X123661Y1685718D02*
X110180Y1688140D01*
G01X110890Y1707038D02*
X105901D01*
G01X105899Y1705638D02*
X110890D01*
G01X112266Y1706604D02*
G03X110890Y1707038I-1376J-1966D01*
G01Y1705638D02*
G02X111463Y1705457I-1J-1000D01*
G01D02*
X130611Y1692050D01*
G01X111463Y1705457D02*
X130611Y1692050D01*
G01X110890Y1705638D02*
G02X111463Y1705457I-1J-1000D01*
G01X112266Y1706604D02*
G03X110890Y1707038I-1376J-1966D01*
G01X105899Y1705638D02*
X110890D01*
G01Y1707038D02*
X105901D01*
G01X62749Y1766259D02*
X42757Y1652885D01*
G01X64074Y1765710D02*
X44083Y1652336D01*
G01X64074Y1765710D02*
X44083Y1652336D01*
G01X62749Y1766259D02*
X42757Y1652885D01*
G01X58787Y1852415D02*
X39281Y1741795D01*
G01X58787Y1852415D02*
X39281Y1741795D01*
G01X54887Y1817453D02*
X39343Y1729237D01*
G01X56212Y1816904D02*
X40668Y1728688D01*
G01X63241Y1793092D02*
X68230Y1800219D01*
G01X59539Y1785364D02*
X69236Y1799213D01*
G01X58392Y1786167D02*
X63241Y1793092D01*
G01X59539Y1785364D02*
X69236Y1799213D01*
G01X58214Y1785913D02*
X58391Y1786167D01*
G01X59539Y1785364D02*
X69236Y1799213D01*
G01X59539Y1785364D02*
X69236Y1799213D01*
G01X63241Y1793092D02*
X68230Y1800219D01*
G01X58392Y1786167D02*
X63241Y1793092D01*
G01X58214Y1785913D02*
X58391Y1786167D01*
G01X107367Y1793781D02*
X116471Y1787407D01*
G01X106818Y1792456D02*
X115465Y1786401D01*
G01X91963Y1796498D02*
X107367Y1793781D01*
G01X91963Y1795076D02*
X106818Y1792456D01*
G01X76783Y1789008D02*
X85976Y1795442D01*
G01X77789Y1788002D02*
X86525Y1794117D01*
G01X75002Y1786465D02*
X76783Y1789008D01*
G01X76008Y1785459D02*
X77789Y1788002D01*
G01X66478Y1780498D02*
X75002Y1786465D01*
G01X67484Y1779492D02*
X76008Y1785459D01*
G01X59500Y1770530D02*
X66478Y1780498D01*
G01X60825Y1769981D02*
X67484Y1779492D01*
G01X106818Y1792456D02*
X115465Y1786401D01*
G01X107367Y1793781D02*
X116471Y1787407D01*
G01X91963Y1795076D02*
X106818Y1792456D01*
G01X91963Y1796498D02*
X107367Y1793781D01*
G01X77789Y1788002D02*
X86525Y1794117D01*
G01X76783Y1789008D02*
X85976Y1795442D01*
G01X76008Y1785459D02*
X77789Y1788002D01*
G01X75002Y1786465D02*
X76783Y1789008D01*
G01X67484Y1779492D02*
X76008Y1785459D01*
G01X66478Y1780498D02*
X75002Y1786465D01*
G01X60825Y1769981D02*
X67484Y1779492D01*
G01X59500Y1770530D02*
X66478Y1780498D01*
G01X56212Y1816904D02*
X40668Y1728688D01*
G01X54887Y1817453D02*
X39343Y1729237D01*
G01X110883Y1725936D02*
X128743Y1713431D01*
G01X112038Y1723418D02*
X110441Y1724536D01*
G01X105900Y1725936D02*
X110883D01*
G01X110441Y1724536D02*
X105900D01*
G01X110441D02*
X105900D01*
G01Y1725936D02*
X110883D01*
G01X112038Y1723418D02*
X110441Y1724536D01*
G01X110883Y1725936D02*
X128743Y1713431D01*
G01X110883Y1725936D02*
X128743Y1713431D01*
G01X110883Y1725936D02*
X128743Y1713431D01*
G01X110883Y1725936D02*
X128743Y1713431D01*
G01X110883Y1725936D02*
X128743Y1713431D01*
G01X110883Y1725936D02*
X128743Y1713431D01*
G01X110883Y1725936D02*
X128743Y1713431D01*
G01X109123Y1776329D02*
X112169Y1775791D01*
G01X111620Y1774466D02*
X109000Y1774929D01*
G01X105901Y1776329D02*
X109123D01*
G01X109000Y1774929D02*
X105899D01*
G01X109000D02*
X105899D01*
G01X105901Y1776329D02*
X109123D01*
G01X111620Y1774466D02*
X109000Y1774929D01*
G01X109123Y1776329D02*
X112169Y1775791D01*
G01X69854Y1776407D02*
X62749Y1766259D01*
G01X70860Y1775401D02*
X64074Y1765710D01*
G01X79012Y1782819D02*
X69854Y1776407D01*
G01X80018Y1781813D02*
X70860Y1775401D01*
G01X82995Y1788506D02*
X79012Y1782819D01*
G01X84000Y1787500D02*
X80018Y1781813D01*
G01X83341Y1788748D02*
X82995Y1788506D01*
G01X85476Y1788534D02*
X84000Y1787500D01*
G01X83934Y1789164D02*
X83341Y1788748D01*
G01X85476Y1788534D02*
X84000Y1787500D01*
G01X84927Y1789859D02*
X83934Y1789164D01*
G01X85476Y1788534D02*
X84000Y1787500D01*
G01X91556Y1791028D02*
X84927Y1789859D01*
G01X91556Y1789606D02*
X85476Y1788534D01*
G01X105293Y1788606D02*
X91556Y1791028D01*
G01X104744Y1787281D02*
X91556Y1789606D01*
G01X116828Y1780530D02*
X105293Y1788606D01*
G01X115822Y1779524D02*
X104744Y1787281D01*
G01X70860Y1775401D02*
X64074Y1765710D01*
G01X69854Y1776407D02*
X62749Y1766259D01*
G01X80018Y1781813D02*
X70860Y1775401D01*
G01X79012Y1782819D02*
X69854Y1776407D01*
G01X84000Y1787500D02*
X80018Y1781813D01*
G01X82995Y1788506D02*
X79012Y1782819D01*
G01X85476Y1788534D02*
X84000Y1787500D01*
G01X83341Y1788748D02*
X82995Y1788506D01*
G01X83934Y1789164D02*
X83341Y1788748D01*
G01X84927Y1789859D02*
X83934Y1789164D01*
G01X91556Y1789606D02*
X85476Y1788534D01*
G01X91556Y1791028D02*
X84927Y1789859D01*
G01X104744Y1787281D02*
X91556Y1789606D01*
G01X105293Y1788606D02*
X91556Y1791028D01*
G01X115822Y1779524D02*
X104744Y1787281D01*
G01X116828Y1780530D02*
X105293Y1788606D01*
G01X116828Y1780530D02*
X105293Y1788606D01*
G01X89907Y1909632D02*
X51733Y1855121D01*
G01X88901Y1910638D02*
X50408Y1855670D01*
G01X88901Y1910638D02*
X50408Y1855670D01*
G01X89907Y1909632D02*
X51733Y1855121D01*
G01X76185Y1883476D02*
X55339Y1853704D01*
G01X75179Y1884482D02*
X54014Y1854253D01*
G01X75179Y1884482D02*
X54014Y1854253D01*
G01X76185Y1883476D02*
X55339Y1853704D01*
G01X72499Y1871998D02*
X58787Y1852415D01*
G01X71493Y1873004D02*
X57462Y1852964D01*
G01X71493Y1873004D02*
X57462Y1852964D01*
G01X72499Y1871998D02*
X58787Y1852415D01*
G01X62439Y1828242D02*
X54887Y1817453D01*
G01X63445Y1827236D02*
X56212Y1816904D01*
G01X77222Y1838592D02*
X62439Y1828242D01*
G01X77771Y1837267D02*
X63445Y1827236D01*
G01X107381Y1843910D02*
X77222Y1838592D01*
G01X107085Y1842435D02*
X77771Y1837267D01*
G01X107648Y1843810D02*
X107492Y1843833D01*
G01X133408Y1837845D02*
X107399Y1842430D01*
G01X133531Y1839245D02*
X107648Y1843810D01*
G01X133408Y1837845D02*
X107399Y1842430D01*
G01X65915Y1819389D02*
X58534Y1808812D01*
G01X66921Y1818384D02*
X59859Y1808264D01*
G01X70539Y1822626D02*
X65915Y1819389D01*
G01X71088Y1821301D02*
X66921Y1818384D01*
G01X80469Y1824376D02*
X70539Y1822626D01*
G01X80713Y1822997D02*
X71088Y1821301D01*
G01X81304Y1824376D02*
G03X80469I-417J-2363D01*
G01X81061Y1822996D02*
G03X80713Y1822997I-177J-984D01*
G01X90584Y1822737D02*
X81304Y1824376D01*
G01X90274Y1821370D02*
X81061Y1822996D01*
G01X90853Y1822662D02*
X90584Y1822737D01*
G01X90274Y1821370D02*
X81061Y1822996D01*
G01X91137Y1822545D02*
X90853Y1822662D01*
G01X91373Y1820932D02*
X90602Y1821251D01*
G01X91978Y1822197D02*
X91137Y1822545D01*
G01X90602Y1821251D02*
X90396Y1821336D01*
G01X91373Y1820932D02*
X90602Y1821251D01*
G01X92442Y1821943D02*
X91978Y1822197D01*
G01X91702Y1820752D02*
X91373Y1820932D01*
G01X109792Y1809797D02*
X92442Y1821943D01*
G01X108989Y1808648D02*
X91702Y1820752D01*
G01X110000Y1809650D02*
X109792Y1809796D01*
G01X108989Y1808648D02*
X91702Y1820752D01*
G01X110136Y1809452D02*
X110000Y1809646D01*
G01X143604Y1759218D02*
X108992Y1808645D01*
G01X144754Y1760019D02*
X110138Y1809450D01*
G01X143604Y1759218D02*
X108992Y1808645D01*
G01X66921Y1818384D02*
X59859Y1808264D01*
G01X65915Y1819389D02*
X58534Y1808812D01*
G01X71088Y1821301D02*
X66921Y1818384D01*
G01X70539Y1822626D02*
X65915Y1819389D01*
G01X80713Y1822997D02*
X71088Y1821301D01*
G01X80469Y1824376D02*
X70539Y1822626D01*
G01X81061Y1822996D02*
G03X80713Y1822997I-177J-984D01*
G01X81304Y1824376D02*
G03X80469I-417J-2363D01*
G01X90274Y1821370D02*
X81061Y1822996D01*
G01X90584Y1822737D02*
X81304Y1824376D01*
G01X90853Y1822662D02*
X90584Y1822737D01*
G01X90602Y1821251D02*
X90396Y1821336D01*
G01X91978Y1822197D02*
X91137Y1822545D01*
G01X91373Y1820932D02*
X90602Y1821251D01*
G01X91137Y1822545D02*
X90853Y1822662D01*
G01X91978Y1822197D02*
X91137Y1822545D01*
G01X91702Y1820752D02*
X91373Y1820932D01*
G01X92442Y1821943D02*
X91978Y1822197D01*
G01X108989Y1808648D02*
X91702Y1820752D01*
G01X109792Y1809797D02*
X92442Y1821943D01*
G01X110000Y1809650D02*
X109792Y1809796D01*
G01X143604Y1759218D02*
X108992Y1808645D01*
G01X110136Y1809452D02*
X110000Y1809646D01*
G01X144754Y1760019D02*
X110138Y1809450D01*
G01X106334Y1799622D02*
X118099Y1791384D01*
G01X93766Y1806714D02*
X117295Y1790236D01*
G01X94569Y1807861D02*
X106334Y1799622D01*
G01X93766Y1806714D02*
X117295Y1790236D01*
G01X93609Y1808259D02*
G02X94569Y1807861I-417J-2364D01*
G01X93366Y1806880D02*
G02X93766Y1806714I-174J-985D01*
G01X86503Y1809511D02*
X93609Y1808259D01*
G01X86503Y1808089D02*
X93366Y1806880D01*
G01X79816Y1808331D02*
X86503Y1809511D01*
G01X80365Y1807006D02*
X86503Y1808089D01*
G01X75754Y1805487D02*
X79816Y1808331D01*
G01X76557Y1804340D02*
X80365Y1807006D01*
G01X68230Y1800219D02*
X75754Y1805487D01*
G01X69236Y1799213D02*
X76557Y1804340D01*
G01X106334Y1799622D02*
X118099Y1791384D01*
G01X93766Y1806714D02*
X117295Y1790236D01*
G01X106334Y1799622D02*
X118099Y1791384D01*
G01X94569Y1807861D02*
X106334Y1799622D01*
G01X93366Y1806880D02*
G02X93766Y1806714I-174J-985D01*
G01X93609Y1808259D02*
G02X94569Y1807861I-417J-2364D01*
G01X86503Y1808089D02*
X93366Y1806880D01*
G01X86503Y1809511D02*
X93609Y1808259D01*
G01X80365Y1807006D02*
X86503Y1808089D01*
G01X79816Y1808331D02*
X86503Y1809511D01*
G01X76557Y1804340D02*
X80365Y1807006D01*
G01X75754Y1805487D02*
X79816Y1808331D01*
G01X69236Y1799213D02*
X76557Y1804340D01*
G01X68230Y1800219D02*
X75754Y1805487D01*
G01X85976Y1795442D02*
X91963Y1796498D01*
G01X86525Y1794117D02*
X91963Y1795076D01*
G01X86525Y1794117D02*
X91963Y1795076D01*
G01X85976Y1795442D02*
X91963Y1796498D01*
G01X63445Y1827236D02*
X56212Y1816904D01*
G01X62439Y1828242D02*
X54887Y1817453D01*
G01X77771Y1837267D02*
X63445Y1827236D01*
G01X77222Y1838592D02*
X62439Y1828242D01*
G01X107085Y1842435D02*
X77771Y1837267D01*
G01X107381Y1843910D02*
X77222Y1838592D01*
G01X133408Y1837845D02*
X107399Y1842430D01*
G01X107648Y1843810D02*
X107492Y1843833D01*
G01X133531Y1839245D02*
X107648Y1843810D01*
G01X106362Y1921154D02*
X89907Y1909632D01*
G01X105813Y1922479D02*
X88901Y1910638D01*
G01X134040Y1926034D02*
X106362Y1921154D01*
G01X133917Y1927434D02*
X105813Y1922479D01*
G01D02*
X88901Y1910638D01*
G01X106362Y1921154D02*
X89907Y1909632D01*
G01X133917Y1927434D02*
X105813Y1922479D01*
G01X134040Y1926034D02*
X106362Y1921154D01*
G01X102006Y1901556D02*
X76185Y1883476D01*
G01X101457Y1902881D02*
X75179Y1884482D01*
G01X133654Y1907136D02*
X102006Y1901556D01*
G01X133531Y1908536D02*
X101457Y1902881D01*
G01D02*
X75179Y1884482D01*
G01X102006Y1901556D02*
X76185Y1883476D01*
G01X133531Y1908536D02*
X101457Y1902881D01*
G01X133654Y1907136D02*
X102006Y1901556D01*
G01X97387Y1889423D02*
X72499Y1871998D01*
G01X96841Y1890750D02*
X71493Y1873004D01*
G01X112270Y1891986D02*
X97387Y1889423D01*
G01X112273Y1893408D02*
X96841Y1890750D01*
G01D02*
X71493Y1873004D01*
G01X97387Y1889423D02*
X72499Y1871998D01*
G01X112273Y1893408D02*
X96841Y1890750D01*
G01X112270Y1891986D02*
X97387Y1889423D01*
G01X142380Y111807D02*
X115815Y262437D01*
G01X114490Y261888D02*
X140958Y111807D01*
G01X137696Y85244D02*
X142380Y111807D01*
G01X137017Y89456D02*
X136371Y85793D01*
G01X137951Y94753D02*
X137612Y92833D01*
G01X138885Y100051D02*
X138546Y98131D01*
G01X140958Y111807D02*
X139480Y103429D01*
G01X133121Y78708D02*
X137696Y85244D01*
G01X136371Y85793D02*
X132115Y79714D01*
G01X114086Y65381D02*
X133121Y78708D01*
G01X118894Y70457D02*
X113537Y66706D01*
G01X121703Y72424D02*
X120673Y72606D01*
G01X123301Y73542D02*
X121703Y72424D01*
G01X126111Y75510D02*
X125080Y75692D01*
G01X127708Y76628D02*
X126111Y75510D01*
G01X130518Y78596D02*
X129487Y78777D01*
G01X132115Y79714D02*
X130518Y78596D01*
G01X118894Y70457D02*
X113537Y66706D01*
G01X114086Y65381D02*
X133121Y78708D01*
G01X121703Y72424D02*
X120673Y72606D01*
G01X114086Y65381D02*
X133121Y78708D01*
G01X123301Y73542D02*
X121703Y72424D01*
G01X114086Y65381D02*
X133121Y78708D01*
G01X126111Y75510D02*
X125080Y75692D01*
G01X114086Y65381D02*
X133121Y78708D01*
G01X127708Y76628D02*
X126111Y75510D01*
G01X114086Y65381D02*
X133121Y78708D01*
G01X130518Y78596D02*
X129487Y78777D01*
G01X114086Y65381D02*
X133121Y78708D01*
G01X132115Y79714D02*
X130518Y78596D01*
G01X114086Y65381D02*
X133121Y78708D01*
G01X136371Y85793D02*
X132115Y79714D01*
G01X133121Y78708D02*
X137696Y85244D01*
G01X137017Y89456D02*
X136371Y85793D01*
G01X137696Y85244D02*
X142380Y111807D01*
G01X137951Y94753D02*
X137612Y92833D01*
G01X137696Y85244D02*
X142380Y111807D01*
G01X138885Y100051D02*
X138546Y98131D01*
G01X137696Y85244D02*
X142380Y111807D01*
G01X140958D02*
X139480Y103429D01*
G01X137696Y85244D02*
X142380Y111807D01*
G01X114490Y261888D02*
X140958Y111807D01*
G01X142380D02*
X115815Y262437D01*
G01X133710Y105450D02*
X136596Y121818D01*
G01X132385Y105999D02*
X135174Y121818D01*
G01X121993Y88715D02*
X133710Y105450D01*
G01X130245Y102942D02*
X132385Y105999D01*
G01X127159Y98535D02*
X128277Y100132D01*
G01X124073Y94128D02*
X125191Y95725D01*
G01X120987Y89721D02*
X122105Y91318D01*
G01X117729Y85730D02*
X121993Y88715D01*
G01X117051Y86965D02*
X120987Y89721D01*
G01X114057Y84206D02*
X117729Y85730D01*
G01X113661Y85558D02*
X117051Y86965D01*
G01X132385Y105999D02*
X135174Y121818D01*
G01X133710Y105450D02*
X136596Y121818D01*
G01X130245Y102942D02*
X132385Y105999D01*
G01X121993Y88715D02*
X133710Y105450D01*
G01X127159Y98535D02*
X128277Y100132D01*
G01X121993Y88715D02*
X133710Y105450D01*
G01X124073Y94128D02*
X125191Y95725D01*
G01X121993Y88715D02*
X133710Y105450D01*
G01X120987Y89721D02*
X122105Y91318D01*
G01X121993Y88715D02*
X133710Y105450D01*
G01X117051Y86965D02*
X120987Y89721D01*
G01X117729Y85730D02*
X121993Y88715D01*
G01X113661Y85558D02*
X117051Y86965D01*
G01X114057Y84206D02*
X117729Y85730D01*
G01X129398Y120355D02*
X130470Y126434D01*
G01X118350Y104583D02*
X129398Y120355D01*
G01X126954Y119307D02*
X128073Y120904D01*
G01X123867Y114901D02*
X124986Y116498D01*
G01X120780Y110494D02*
X121899Y112091D01*
G01X117344Y105589D02*
X118812Y107685D01*
G01X116970Y103617D02*
X118350Y104583D01*
G01X116421Y104942D02*
X117344Y105589D01*
G01X129398Y120355D02*
X130470Y126434D01*
G01X126954Y119307D02*
X128073Y120904D01*
G01X118350Y104583D02*
X129398Y120355D01*
G01X123867Y114901D02*
X124986Y116498D01*
G01X118350Y104583D02*
X129398Y120355D01*
G01X120780Y110494D02*
X121899Y112091D01*
G01X118350Y104583D02*
X129398Y120355D01*
G01X117344Y105589D02*
X118812Y107685D01*
G01X118350Y104583D02*
X129398Y120355D01*
G01X116421Y104942D02*
X117344Y105589D01*
G01X116970Y103617D02*
X118350Y104583D01*
G01X136596Y121818D02*
X112911Y256104D01*
G01X133305Y132414D02*
X111586Y255555D01*
G01X134239Y127116D02*
X133901Y129037D01*
G01X135174Y121818D02*
X134835Y123738D01*
G01X133305Y132414D02*
X111586Y255555D01*
G01X136596Y121818D02*
X112911Y256104D01*
G01X134239Y127116D02*
X133901Y129037D01*
G01X136596Y121818D02*
X112911Y256104D01*
G01X135174Y121818D02*
X134835Y123738D01*
G01X136596Y121818D02*
X112911Y256104D01*
G01X128073Y120904D02*
X129048Y126435D01*
G01X128073Y120904D02*
X129048Y126435D01*
G01X116305Y155566D02*
X113110Y153330D01*
G01X115299Y156572D02*
X112561Y154655D01*
G01X117761Y157646D02*
X116305Y155566D01*
G01X116436Y158195D02*
X115299Y156572D01*
G01X118325Y160848D02*
X117761Y157646D01*
G01X116946Y161091D02*
X116436Y158195D01*
G01X118326Y161682D02*
G02Y160848I-2364J-417D01*
G01X116947Y161440D02*
G02Y161092I-985J-174D01*
G01X115299Y156572D02*
X112561Y154655D01*
G01X116305Y155566D02*
X113110Y153330D01*
G01X116436Y158195D02*
X115299Y156572D01*
G01X117761Y157646D02*
X116305Y155566D01*
G01X116946Y161091D02*
X116436Y158195D01*
G01X118325Y160848D02*
X117761Y157646D01*
G01X116947Y161440D02*
G02Y161092I-985J-174D01*
G01X118326Y161682D02*
G02Y160848I-2364J-417D01*
G01X135100Y217197D02*
X138196D01*
G01X134977Y215797D02*
X138194D01*
G01X133266Y217520D02*
X135100Y217197D01*
G01X132717Y216195D02*
X134977Y215797D01*
G01X131491Y218763D02*
X133266Y217520D01*
G01X130485Y217757D02*
X132717Y216195D01*
G01X129411Y221735D02*
X131491Y218763D01*
G01X128883Y220047D02*
X130485Y217757D01*
G01X128086Y221185D02*
X128883Y220047D01*
G01X120258Y273648D02*
X129411Y221735D01*
G01X118933Y273099D02*
X128086Y221185D01*
G01X134977Y215797D02*
X138194D01*
G01X135100Y217197D02*
X138196D01*
G01X132717Y216195D02*
X134977Y215797D01*
G01X133266Y217520D02*
X135100Y217197D01*
G01X130485Y217757D02*
X132717Y216195D01*
G01X131491Y218763D02*
X133266Y217520D01*
G01X128883Y220047D02*
X130485Y217757D01*
G01X129411Y221735D02*
X131491Y218763D01*
G01X128086Y221185D02*
X128883Y220047D01*
G01X129411Y221735D02*
X131491Y218763D01*
G01X118933Y273099D02*
X128086Y221185D01*
G01X120258Y273648D02*
X129411Y221735D01*
G01X134040Y305386D02*
X118845Y308064D01*
G01X133917Y303986D02*
X118450Y306712D01*
G01X138196Y305386D02*
X134040D01*
G01X138194Y303986D02*
X133917D01*
G01D02*
X118450Y306712D01*
G01X134040Y305386D02*
X118845Y308064D01*
G01X138194Y303986D02*
X133917D01*
G01X138196Y305386D02*
X134040D01*
G01X133653Y286488D02*
X138196D01*
G01X138194Y285088D02*
X133530D01*
G01X125832Y287866D02*
X133653Y286488D01*
G01X133530Y285088D02*
X125283Y286541D01*
G01X125829Y287868D02*
X125832Y287866D01*
G01X125282Y286541D02*
X113407Y294856D01*
G01X114413Y295862D02*
X125829Y287868D01*
G01X125282Y286541D02*
X113407Y294856D01*
G01X125282Y286541D02*
X113407Y294856D01*
G01X125829Y287868D02*
X125832Y287866D01*
G01X114413Y295862D02*
X125829Y287868D01*
G01X133530Y285088D02*
X125283Y286541D01*
G01X125832Y287866D02*
X133653Y286488D01*
G01X138194Y285088D02*
X133530D01*
G01X133653Y286488D02*
X138196D01*
G01X133654Y267590D02*
X138195D01*
G01Y266190D02*
X133531D01*
G01X131558Y267960D02*
X133654Y267590D01*
G01X133531Y266190D02*
X131009Y266635D01*
G01X126087Y271790D02*
X131558Y267960D01*
G01X131009Y266635D02*
X125081Y270784D01*
G01X131009Y266635D02*
X125081Y270784D01*
G01X126087Y271790D02*
X131558Y267960D01*
G01X133531Y266190D02*
X131009Y266635D01*
G01X131558Y267960D02*
X133654Y267590D01*
G01X138195Y266190D02*
X133531D01*
G01X133654Y267590D02*
X138195D01*
G01X178387Y405122D02*
X181645Y423610D01*
G01X177061Y405670D02*
X180223Y423610D01*
G01X172940Y397338D02*
X178387Y405122D01*
G01X171934Y398344D02*
X177061Y405670D01*
G01X157025Y386195D02*
X172940Y397338D01*
G01X156476Y387520D02*
X171934Y398344D01*
G01X177061Y405670D02*
X180223Y423610D01*
G01X178387Y405122D02*
X181645Y423610D01*
G01X171934Y398344D02*
X177061Y405670D01*
G01X172940Y397338D02*
X178387Y405122D01*
G01X156476Y387520D02*
X171934Y398344D01*
G01X157025Y386195D02*
X172940Y397338D01*
G01X170121Y400067D02*
X158924Y392229D01*
G01X158375Y393554D02*
X169115Y401073D01*
G01X174793Y406745D02*
X170121Y400067D01*
G01X169115Y401073D02*
X173468Y407294D01*
G01X176882Y418588D02*
X174793Y406745D01*
G01X173468Y407294D02*
X175460Y418588D01*
G01X173468Y407294D02*
X175460Y418588D01*
G01X176882D02*
X174793Y406745D01*
G01X169115Y401073D02*
X173468Y407294D01*
G01X174793Y406745D02*
X170121Y400067D01*
G01X158375Y393554D02*
X169115Y401073D01*
G01X170121Y400067D02*
X158924Y392229D01*
G01X168125Y403411D02*
X157378Y395884D01*
G01X156829Y397209D02*
X167119Y404417D01*
G01X171237Y407858D02*
X168125Y403411D01*
G01X167119Y404417D02*
X169912Y408407D01*
G01X173017Y417953D02*
X171237Y407858D01*
G01X169912Y408407D02*
X171595Y417953D01*
G01X169912Y408407D02*
X171595Y417953D01*
G01X173017D02*
X171237Y407858D01*
G01X167119Y404417D02*
X169912Y408407D01*
G01X171237Y407858D02*
X168125Y403411D01*
G01X156829Y397209D02*
X167119Y404417D01*
G01X168125Y403411D02*
X157378Y395884D01*
G01X165368Y405842D02*
X156196Y399421D01*
G01X164362Y406848D02*
X155647Y400746D01*
G01X167555Y408968D02*
X165368Y405842D01*
G01X166230Y409517D02*
X164362Y406848D01*
G01X169148Y417993D02*
X167555Y408968D01*
G01X167726Y417993D02*
X166230Y409517D01*
G01X164362Y406848D02*
X155647Y400746D01*
G01X165368Y405842D02*
X156196Y399421D01*
G01X166230Y409517D02*
X164362Y406848D01*
G01X167555Y408968D02*
X165368Y405842D01*
G01X167726Y417993D02*
X166230Y409517D01*
G01X169148Y417993D02*
X167555Y408968D01*
G01X167245Y457234D02*
X145890Y578317D01*
G01X165920Y456685D02*
X144565Y577768D01*
G01X178567Y441060D02*
X167245Y457234D01*
G01X177242Y440511D02*
X165920Y456685D01*
G01X181645Y423610D02*
X178567Y441060D01*
G01X180223Y423610D02*
X177242Y440511D01*
G01X165920Y456685D02*
X144565Y577768D01*
G01X167245Y457234D02*
X145890Y578317D01*
G01X177242Y440511D02*
X165920Y456685D01*
G01X178567Y441060D02*
X167245Y457234D01*
G01X180223Y423610D02*
X177242Y440511D01*
G01X181645Y423610D02*
X178567Y441060D01*
G01X118656Y472763D02*
X114198Y470912D01*
G01X117978Y473998D02*
X113801Y472264D01*
G01X126930Y478555D02*
X118656Y472763D01*
G01X119575Y475116D02*
X117978Y473998D01*
G01X122385Y477084D02*
X121355Y477265D01*
G01X125924Y479561D02*
X122385Y477084D01*
G01X135308Y490523D02*
X126930Y478555D01*
G01X133983Y491072D02*
X125924Y479561D01*
G01X172534Y443248D02*
X176882Y418588D01*
G01X175460D02*
X171209Y442699D01*
G01X163511Y456142D02*
X172534Y443248D01*
G01X171209Y442699D02*
X162186Y455593D01*
G01X142141Y577197D02*
X163511Y456142D01*
G01X162186Y455593D02*
X140816Y576648D01*
G01X162186Y455593D02*
X140816Y576648D01*
G01X142141Y577197D02*
X163511Y456142D01*
G01X171209Y442699D02*
X162186Y455593D01*
G01X163511Y456142D02*
X172534Y443248D01*
G01X175460Y418588D02*
X171209Y442699D01*
G01X172534Y443248D02*
X176882Y418588D01*
G01X168766Y442066D02*
X173017Y417953D01*
G01X171595D02*
X167441Y441517D01*
G01X160030Y454540D02*
X168766Y442066D01*
G01X167441Y441517D02*
X158705Y453991D01*
G01X138713Y575484D02*
X160030Y454540D01*
G01X158705Y453991D02*
X137388Y574935D01*
G01X158705Y453991D02*
X137388Y574935D01*
G01X138713Y575484D02*
X160030Y454540D01*
G01X167441Y441517D02*
X158705Y453991D01*
G01X160030Y454540D02*
X168766Y442066D01*
G01X171595Y417953D02*
X167441Y441517D01*
G01X168766Y442066D02*
X173017Y417953D01*
G01X165119Y440843D02*
X169148Y417993D01*
G01X163794Y440294D02*
X167726Y417993D01*
G01X156496Y453158D02*
X165119Y440843D01*
G01X155172Y452607D02*
X163794Y440294D01*
G01X135239Y573790D02*
X156497Y453159D01*
G01X133914Y573241D02*
X155172Y452607D01*
G01X163794Y440294D02*
X167726Y417993D01*
G01X165119Y440843D02*
X169148Y417993D01*
G01X155172Y452607D02*
X163794Y440294D01*
G01X156496Y453158D02*
X165119Y440843D01*
G01X133914Y573241D02*
X155172Y452607D01*
G01X135239Y573790D02*
X156497Y453159D01*
G01X117978Y473998D02*
X113801Y472264D01*
G01X118656Y472763D02*
X114198Y470912D01*
G01X119575Y475116D02*
X117978Y473998D01*
G01X126930Y478555D02*
X118656Y472763D01*
G01X122385Y477084D02*
X121355Y477265D01*
G01X126930Y478555D02*
X118656Y472763D01*
G01X125924Y479561D02*
X122385Y477084D01*
G01X126930Y478555D02*
X118656Y472763D01*
G01X133983Y491072D02*
X125924Y479561D01*
G01X135308Y490523D02*
X126930Y478555D01*
G01X138201Y506934D02*
X135308Y490523D01*
G01X136779Y506934D02*
X133983Y491072D01*
G01X125996Y576115D02*
X138201Y506934D01*
G01X124671Y575566D02*
X136779Y506934D01*
G01D02*
X133983Y491072D01*
G01X138201Y506934D02*
X135308Y490523D01*
G01X124671Y575566D02*
X136779Y506934D01*
G01X125996Y576115D02*
X138201Y506934D01*
G01X131061Y524907D02*
X123128Y569876D01*
G01X129639Y524907D02*
X121803Y569327D01*
G01X127454Y504454D02*
X131061Y524907D01*
G01X126129Y505003D02*
X129639Y524907D01*
G01X119923Y493697D02*
X127454Y504454D01*
G01X122003Y499110D02*
X126129Y505003D01*
G01X118917Y494703D02*
X120035Y496300D01*
G01X114298Y489760D02*
X119923Y493697D01*
G01X113751Y491086D02*
X118917Y494703D01*
G01X129639Y524907D02*
X121803Y569327D01*
G01X131061Y524907D02*
X123128Y569876D01*
G01X126129Y505003D02*
X129639Y524907D01*
G01X127454Y504454D02*
X131061Y524907D01*
G01X122003Y499110D02*
X126129Y505003D01*
G01X119923Y493697D02*
X127454Y504454D01*
G01X118917Y494703D02*
X120035Y496300D01*
G01X119923Y493697D02*
X127454Y504454D01*
G01X113751Y491086D02*
X118917Y494703D01*
G01X114298Y489760D02*
X119923Y493697D01*
G01X120051Y553446D02*
X116810Y571865D01*
G01X118629Y553446D02*
X115485Y571316D01*
G01X116150Y531317D02*
X120051Y553446D01*
G01X117182Y545239D02*
X118629Y553446D01*
G01X116248Y539942D02*
X116587Y541862D01*
G01X114728Y531317D02*
X115653Y536564D01*
G01X117589Y523157D02*
X116150Y531317D01*
G01X116189Y523034D02*
X114728Y531317D01*
G01X117589Y519617D02*
Y523157D01*
G01X116189Y519678D02*
Y523034D01*
G01X116249Y511954D02*
X117600Y519615D01*
G01X114924Y512503D02*
X116189Y519678D01*
G01X115042Y510229D02*
X116249Y511954D01*
G01X114036Y511235D02*
X114924Y512503D01*
G01X112291Y508304D02*
X115042Y510229D01*
G01X111742Y509629D02*
X114036Y511235D01*
G01X118629Y553446D02*
X115485Y571316D01*
G01X120051Y553446D02*
X116810Y571865D01*
G01X117182Y545239D02*
X118629Y553446D01*
G01X116150Y531317D02*
X120051Y553446D01*
G01X116248Y539942D02*
X116587Y541862D01*
G01X116150Y531317D02*
X120051Y553446D01*
G01X114728Y531317D02*
X115653Y536564D01*
G01X116150Y531317D02*
X120051Y553446D01*
G01X116189Y523034D02*
X114728Y531317D01*
G01X117589Y523157D02*
X116150Y531317D01*
G01X116189Y519678D02*
Y523034D01*
G01X117589Y519617D02*
Y523157D01*
G01X114924Y512503D02*
X116189Y519678D01*
G01X116249Y511954D02*
X117600Y519615D01*
G01X114036Y511235D02*
X114924Y512503D01*
G01X115042Y510229D02*
X116249Y511954D01*
G01X111742Y509629D02*
X114036Y511235D01*
G01X112291Y508304D02*
X115042Y510229D01*
G01X130604Y625851D02*
X129021Y634823D01*
G01X129279Y625302D02*
X127599Y634823D01*
G01X131510Y624556D02*
X130604Y625851D01*
G01X130504Y623550D02*
X129279Y625302D01*
G01X133470Y623184D02*
X131510Y624556D01*
G01X132921Y621859D02*
X130504Y623550D01*
G01X136165Y622709D02*
X133470Y623184D01*
G01X136042Y621309D02*
X132921Y621859D01*
G01X138196Y622709D02*
X136165D01*
G01X138194Y621309D02*
X136042D01*
G01X129279Y625302D02*
X127599Y634823D01*
G01X130604Y625851D02*
X129021Y634823D01*
G01X130504Y623550D02*
X129279Y625302D01*
G01X131510Y624556D02*
X130604Y625851D01*
G01X132921Y621859D02*
X130504Y623550D01*
G01X133470Y623184D02*
X131510Y624556D01*
G01X136042Y621309D02*
X132921Y621859D01*
G01X136165Y622709D02*
X133470Y623184D01*
G01X138194Y621309D02*
X136042D01*
G01X138196Y622709D02*
X136165D01*
G01X129446Y601798D02*
X116117Y677386D01*
G01X128121Y601249D02*
X114792Y676837D01*
G01X145890Y578317D02*
X129446Y601798D01*
G01X144565Y577768D02*
X128121Y601249D01*
G01D02*
X114792Y676837D01*
G01X129446Y601798D02*
X116117Y677386D01*
G01X144565Y577768D02*
X128121Y601249D01*
G01X145890Y578317D02*
X129446Y601798D01*
G01X114616Y592376D02*
X125996Y576115D01*
G01X113291Y591827D02*
X124671Y575566D01*
G01X125879Y600423D02*
X142141Y577197D01*
G01X140816Y576648D02*
X124554Y599874D01*
G01X112676Y675312D02*
X125879Y600423D01*
G01X112676Y675312D02*
X125879Y600423D01*
G01X140816Y576648D02*
X124554Y599874D01*
G01X125879Y600423D02*
X142141Y577197D01*
G01X122344Y598859D02*
X138713Y575484D01*
G01X137388Y574935D02*
X121019Y598310D01*
G01X137388Y574935D02*
X121019Y598310D01*
G01X122344Y598859D02*
X138713Y575484D01*
G01X118665Y597445D02*
X135239Y573790D01*
G01X117340Y596896D02*
X133914Y573241D01*
G01X117340Y596896D02*
X133914Y573241D01*
G01X118665Y597445D02*
X135239Y573790D01*
G01X113291Y591827D02*
X124671Y575566D01*
G01X114616Y592376D02*
X125996Y576115D01*
G01X111808Y586047D02*
X111785Y586178D01*
G01X123128Y569876D02*
X111808Y586048D01*
G01Y586047D02*
X111785Y586178D01*
G01X123128Y569876D02*
X111808Y586048D01*
G01X113618Y565533D02*
X113066Y568662D01*
G01X111741Y568113D02*
X112196Y565533D01*
G01X112874Y561315D02*
X113618Y565533D01*
G01X112196D02*
X111548Y561864D01*
G01X111880Y559893D02*
X112874Y561315D01*
G01X111736Y559688D02*
X111878Y559890D01*
G01X111880Y559893D02*
X112874Y561315D01*
G01X111736Y559688D02*
X111878Y559890D01*
G01X112196Y565533D02*
X111548Y561864D01*
G01X112874Y561315D02*
X113618Y565533D01*
G01X111741Y568113D02*
X112196Y565533D01*
G01X113618D02*
X113066Y568662D01*
G01X133777Y692000D02*
X138196D01*
G01X138194Y690600D02*
X133654D01*
G01X125115Y693528D02*
X133777Y692000D01*
G01X133654Y690600D02*
X124566Y692203D01*
G01X118718Y698008D02*
X125115Y693528D01*
G01X124566Y692203D02*
X117712Y697002D01*
G01X124566Y692203D02*
X117712Y697002D01*
G01X118718Y698008D02*
X125115Y693528D01*
G01X133654Y690600D02*
X124566Y692203D01*
G01X125115Y693528D02*
X133777Y692000D01*
G01X138194Y690600D02*
X133654D01*
G01X133777Y692000D02*
X138196D01*
G01X133777Y673102D02*
X138195D01*
G01Y671702D02*
X133654D01*
G01X131407Y673520D02*
X133777Y673102D01*
G01X133654Y671702D02*
X130858Y672195D01*
G01X130156Y674396D02*
X131407Y673520D01*
G01X130858Y672195D02*
X129150Y673390D01*
G01X130858Y672195D02*
X129150Y673390D01*
G01X130156Y674396D02*
X131407Y673520D01*
G01X133654Y671702D02*
X130858Y672195D01*
G01X131407Y673520D02*
X133777Y673102D01*
G01X138195Y671702D02*
X133654D01*
G01X133777Y673102D02*
X138195D01*
G01X130525Y643351D02*
X124886Y675338D01*
G01X129103Y643351D02*
X123561Y674789D01*
G01X129021Y634823D02*
X130525Y643351D01*
G01X127599Y634823D02*
X129103Y643351D01*
G01D02*
X123561Y674789D01*
G01X130525Y643351D02*
X124886Y675338D01*
G01X127599Y634823D02*
X129103Y643351D01*
G01X129021Y634823D02*
X130525Y643351D01*
G01X134163Y710898D02*
X138196D01*
G01X138194Y709498D02*
X134040D01*
G01X117915Y713764D02*
X134163Y710898D01*
G01X134040Y709498D02*
X117366Y712439D01*
G01X134040Y709498D02*
X117366Y712439D01*
G01X117915Y713764D02*
X134163Y710898D01*
G01X138194Y709498D02*
X134040D01*
G01X134163Y710898D02*
X138196D01*
G01X150414Y852318D02*
X163952Y832984D01*
G01X153613Y845308D02*
X152494Y846905D01*
G01X150414Y852318D02*
X163952Y832984D01*
G01X156699Y840901D02*
X155580Y842498D01*
G01X150414Y852318D02*
X163952Y832984D01*
G01X162627Y832435D02*
X158666Y838091D01*
G01X150414Y852318D02*
X163952Y832984D01*
G01X164246Y823251D02*
X162627Y832435D01*
G01X163952Y832984D02*
X165668Y823251D01*
G01X163201Y817320D02*
X164246Y823251D01*
G01X165668D02*
X164526Y816771D01*
G01X159464Y811983D02*
X163201Y817320D01*
G01X164526Y816771D02*
X160470Y810977D01*
G01X157867Y810864D02*
X159464Y811983D01*
G01X160470Y810977D02*
X146786Y801392D01*
G01X156836Y811046D02*
X157867Y810864D01*
G01X160470Y810977D02*
X146786Y801392D01*
G01X146237Y802717D02*
X155057Y808896D01*
G01X160470Y810977D02*
X146786Y801392D01*
G01X160470Y810977D02*
X146786Y801392D01*
G01X157867Y810864D02*
X159464Y811983D01*
G01X156836Y811046D02*
X157867Y810864D01*
G01X146237Y802717D02*
X155057Y808896D01*
G01X164526Y816771D02*
X160470Y810977D01*
G01X159464Y811983D02*
X163201Y817320D01*
G01X165668Y823251D02*
X164526Y816771D01*
G01X163201Y817320D02*
X164246Y823251D01*
G01X163952Y832984D02*
X165668Y823251D01*
G01X164246D02*
X162627Y832435D01*
G01X150414Y852318D02*
X163952Y832984D01*
G01X153613Y845308D02*
X152494Y846905D01*
G01X156699Y840901D02*
X155580Y842498D01*
G01X162627Y832435D02*
X158666Y838091D01*
G01X169517Y831625D02*
X137460Y877406D01*
G01X169517Y831625D02*
X137460Y877406D01*
G01X169517Y831625D02*
X137460Y877406D01*
G01X168192Y831076D02*
X145712Y863179D01*
G01X169517Y831625D02*
X137460Y877406D01*
G01X169469Y823836D02*
X168192Y831076D01*
G01X170891Y823836D02*
X169517Y831625D01*
G01X167819Y814485D02*
X169469Y823836D01*
G01X169144Y813936D02*
X170891Y823836D01*
G01X163419Y808203D02*
X167819Y814485D01*
G01X164425Y807197D02*
X169144Y813936D01*
G01X161707Y807005D02*
X163419Y808203D01*
G01X162511Y805858D02*
X164425Y807197D01*
G01X160676Y807186D02*
X161707Y807005D01*
G01X152273Y798688D02*
X162511Y805857D01*
G01X157300Y803919D02*
X158897Y805037D01*
G01X152273Y798688D02*
X162511Y805857D01*
G01X156269Y804100D02*
X157300Y803919D01*
G01X152273Y798688D02*
X162511Y805857D01*
G01X151724Y800013D02*
X154490Y801951D01*
G01X152273Y798688D02*
X162511Y805857D01*
G01X169517Y831625D02*
X137460Y877406D01*
G01X168192Y831076D02*
X145712Y863179D01*
G01X170891Y823836D02*
X169517Y831625D01*
G01X169469Y823836D02*
X168192Y831076D01*
G01X169144Y813936D02*
X170891Y823836D01*
G01X167819Y814485D02*
X169469Y823836D01*
G01X164425Y807197D02*
X169144Y813936D01*
G01X163419Y808203D02*
X167819Y814485D01*
G01X162511Y805858D02*
X164425Y807197D01*
G01X161707Y807005D02*
X163419Y808203D01*
G01X152273Y798688D02*
X162511Y805857D01*
G01X160676Y807186D02*
X161707Y807005D01*
G01X157300Y803919D02*
X158897Y805037D01*
G01X156269Y804100D02*
X157300Y803919D01*
G01X151724Y800013D02*
X154490Y801951D01*
G01X165251Y804625D02*
X153604Y796470D01*
G01X166257Y803619D02*
X154153Y795145D01*
G01X171864Y814068D02*
X165251Y804625D01*
G01X173189Y813519D02*
X166257Y803619D01*
G01X173567Y823740D02*
X171864Y814068D01*
G01X174989Y823740D02*
X173189Y813519D01*
G01X172100Y832054D02*
X173567Y823740D01*
G01X173425Y832603D02*
X174989Y823740D01*
G01X128773Y893937D02*
X172100Y832054D01*
G01X120522Y908164D02*
X173425Y832603D01*
G01X120522Y908164D02*
X173425Y832603D01*
G01X120522Y908164D02*
X173425Y832603D01*
G01X120522Y908164D02*
X173425Y832603D01*
G01X166257Y803619D02*
X154153Y795145D01*
G01X165251Y804625D02*
X153604Y796470D01*
G01X173189Y813519D02*
X166257Y803619D01*
G01X171864Y814068D02*
X165251Y804625D01*
G01X174989Y823740D02*
X173189Y813519D01*
G01X173567Y823740D02*
X171864Y814068D01*
G01X173425Y832603D02*
X174989Y823740D01*
G01X172100Y832054D02*
X173567Y823740D01*
G01X120522Y908164D02*
X173425Y832603D01*
G01X128773Y893937D02*
X172100Y832054D01*
G01X175084Y836884D02*
X123639Y910359D01*
G01X176409Y837433D02*
X124964Y910908D01*
G01X177342Y824070D02*
X175084Y836884D01*
G01X178764Y824070D02*
X176409Y837433D01*
G01X175224Y812050D02*
X177342Y824070D01*
G01X176549Y811501D02*
X178764Y824070D01*
G01X168347Y802229D02*
X175224Y812050D01*
G01X169353Y801223D02*
X176549Y811501D01*
G01X155350Y793127D02*
X168347Y802229D01*
G01X155899Y791802D02*
X169353Y801223D01*
G01X176409Y837433D02*
X124964Y910908D01*
G01X175084Y836884D02*
X123639Y910359D01*
G01X178764Y824070D02*
X176409Y837433D01*
G01X177342Y824070D02*
X175084Y836884D01*
G01X176549Y811501D02*
X178764Y824070D01*
G01X175224Y812050D02*
X177342Y824070D01*
G01X169353Y801223D02*
X176549Y811501D01*
G01X168347Y802229D02*
X175224Y812050D01*
G01X155899Y791802D02*
X169353Y801223D01*
G01X155350Y793127D02*
X168347Y802229D01*
G01X151235Y952998D02*
X229506Y841193D01*
G01X149910Y952449D02*
X228500Y840187D01*
G01X149910Y952449D02*
X228500Y840187D01*
G01X151235Y952998D02*
X229506Y841193D01*
G01X148589Y946303D02*
X223905Y838767D01*
G01X147264Y945754D02*
X222899Y837761D01*
G01X147264Y945754D02*
X222899Y837761D01*
G01X148589Y946303D02*
X223905Y838767D01*
G01X144990Y945211D02*
X221278Y836270D01*
G01X143665Y944662D02*
X220274Y835263D01*
G01X143665Y944662D02*
X220274Y835263D01*
G01X144990Y945211D02*
X221278Y836270D01*
G01X355144Y630453D02*
X136981Y941931D01*
G01X354138Y629447D02*
X135656Y941382D01*
G01X354138Y629447D02*
X135656Y941382D01*
G01X355144Y630453D02*
X136981Y941931D01*
G01X352904Y627265D02*
X133071Y941253D01*
G01X351897Y626259D02*
X131746Y940703D01*
G01X351897Y626259D02*
X131746Y940703D01*
G01X352904Y627265D02*
X133071Y941253D01*
G01X218531Y833681D02*
X141603Y943590D01*
G01X217525Y832675D02*
X140277Y943043D01*
G01X217525Y832675D02*
X140277Y943043D01*
G01X218531Y833681D02*
X141603Y943590D01*
G01X118071Y873254D02*
X115959Y874733D01*
G01X116508Y876058D02*
X150414Y852318D01*
G01X120881Y871286D02*
X119850Y871104D01*
G01X116508Y876058D02*
X150414Y852318D01*
G01X122478Y870168D02*
X120881Y871286D01*
G01X116508Y876058D02*
X150414Y852318D01*
G01X125288Y868200D02*
X124258Y868019D01*
G01X116508Y876058D02*
X150414Y852318D01*
G01X126886Y867082D02*
X125288Y868200D01*
G01X116508Y876058D02*
X150414Y852318D01*
G01X129695Y865115D02*
X128665Y864933D01*
G01X116508Y876058D02*
X150414Y852318D01*
G01X149408Y851312D02*
X129695Y865115D01*
G01X116508Y876058D02*
X150414Y852318D01*
G01X150527Y849715D02*
X149408Y851312D01*
G01X150527Y849715D02*
X149408Y851312D01*
G01X116508Y876058D02*
X150414Y852318D01*
G01X118071Y873254D02*
X115959Y874733D01*
G01X120881Y871286D02*
X119850Y871104D01*
G01X122478Y870168D02*
X120881Y871286D01*
G01X125288Y868200D02*
X124258Y868019D01*
G01X126886Y867082D02*
X125288Y868200D01*
G01X129695Y865115D02*
X128665Y864933D01*
G01X149408Y851312D02*
X129695Y865115D01*
G01X114848Y891528D02*
X113818Y891347D01*
G01X116446Y890410D02*
X114848Y891528D01*
G01X119255Y888443D02*
X118225Y888261D01*
G01X136454Y876400D02*
X119255Y888443D01*
G01X137573Y874803D02*
X136454Y876400D01*
G01X140659Y870396D02*
X139540Y871993D01*
G01X143745Y865989D02*
X142626Y867586D01*
G01X114848Y891528D02*
X113818Y891347D01*
G01X116446Y890410D02*
X114848Y891528D01*
G01X119255Y888443D02*
X118225Y888261D01*
G01X136454Y876400D02*
X119255Y888443D01*
G01X137573Y874803D02*
X136454Y876400D01*
G01X140659Y870396D02*
X139540Y871993D01*
G01X143745Y865989D02*
X142626Y867586D01*
G01X129661Y939284D02*
X350170Y624477D01*
G01X128336Y938735D02*
X349165Y623470D01*
G01X128336Y938735D02*
X349165Y623470D01*
G01X129661Y939284D02*
X350170Y624477D01*
G01X125687Y898344D02*
X126806Y896746D01*
G01X122602Y902751D02*
X123720Y901153D01*
G01X119516Y907158D02*
X120634Y905561D01*
G01X125687Y898344D02*
X126806Y896746D01*
G01X122602Y902751D02*
X123720Y901153D01*
G01X119516Y907158D02*
X120634Y905561D01*
G01X125934Y938273D02*
X347960Y621186D01*
G01X124609Y937724D02*
X346954Y620180D01*
G01X124609Y937724D02*
X346954Y620180D01*
G01X125934Y938273D02*
X347960Y621186D01*
G01X124964Y910908D02*
X116205Y960578D01*
G01X124964Y910908D02*
X116205Y960578D01*
G01X124964Y910908D02*
X116205Y960578D01*
G01X124964Y910908D02*
X116205Y960578D01*
G01X122633Y916062D02*
X122294Y917982D01*
G01X124964Y910908D02*
X116205Y960578D01*
G01X123639Y910359D02*
X123229Y912684D01*
G01X124964Y910908D02*
X116205Y960578D01*
G01X124964Y910908D02*
X116205Y960578D01*
G01X122633Y916062D02*
X122294Y917982D01*
G01X123639Y910359D02*
X123229Y912684D01*
G01X145780Y983914D02*
X151235Y952998D01*
G01X144455Y983365D02*
X149910Y952449D01*
G01X125415Y1013000D02*
X145780Y983914D01*
G01X124090Y1012451D02*
X144455Y983365D01*
G01D02*
X149910Y952449D01*
G01X145780Y983914D02*
X151235Y952998D01*
G01X124090Y1012451D02*
X144455Y983365D01*
G01X125415Y1013000D02*
X145780Y983914D01*
G01X142170Y982730D02*
X148589Y946303D01*
G01X140845Y982181D02*
X147264Y945754D01*
G01X121720Y1011936D02*
X142170Y982730D01*
G01X120395Y1011387D02*
X140845Y982181D01*
G01D02*
X147264Y945754D01*
G01X142170Y982730D02*
X148589Y946303D01*
G01X120395Y1011387D02*
X140845Y982181D01*
G01X121720Y1011936D02*
X142170Y982730D01*
G01X138693Y980913D02*
X144990Y945211D01*
G01X137368Y980364D02*
X143665Y944662D01*
G01X128273Y995793D02*
X138693Y980913D01*
G01X116883Y1009617D02*
X137368Y980364D01*
G01X116883Y1009617D02*
X137368Y980364D01*
G01D02*
X143665Y944662D01*
G01X138693Y980913D02*
X144990Y945211D01*
G01X116883Y1009617D02*
X137368Y980364D01*
G01X128273Y995793D02*
X138693Y980913D01*
G01X136981Y941931D02*
X130692Y977587D01*
G01X135656Y941382D02*
X129367Y977038D01*
G01X135656Y941382D02*
X129367Y977038D01*
G01X136981Y941931D02*
X130692Y977587D01*
G01X133071Y941253D02*
X126940Y976013D01*
G01X131746Y940703D02*
X125590Y975606D01*
G01X131746Y940703D02*
X125590Y975606D01*
G01X133071Y941253D02*
X126940Y976013D01*
G01X135116Y979608D02*
X114644Y1008847D01*
G01X133969Y978804D02*
X113319Y1008298D01*
G01X135294Y979354D02*
X135116Y979609D01*
G01X133969Y978804D02*
X113319Y1008298D01*
G01X141603Y943590D02*
X135294Y979354D01*
G01X140277Y943043D02*
X133969Y978804D01*
G01D02*
X113319Y1008298D01*
G01X135116Y979608D02*
X114644Y1008847D01*
G01X135294Y979354D02*
X135116Y979609D01*
G01X140277Y943043D02*
X133969Y978804D01*
G01X141603Y943590D02*
X135294Y979354D01*
G01X123369Y974974D02*
X129661Y939284D01*
G01X122044Y974425D02*
X128336Y938735D01*
G01X118203Y982352D02*
X123369Y974974D01*
G01X117197Y981346D02*
X122044Y974425D01*
G01D02*
X128336Y938735D01*
G01X123369Y974974D02*
X129661Y939284D01*
G01X117197Y981346D02*
X122044Y974425D01*
G01X118203Y982352D02*
X123369Y974974D01*
G01X120831Y967238D02*
X125934Y938273D01*
G01X119506Y966689D02*
X124609Y937724D01*
G01X116170Y973895D02*
X120831Y967238D01*
G01X115179Y972869D02*
X119506Y966689D01*
G01D02*
X124609Y937724D01*
G01X120831Y967238D02*
X125934Y938273D01*
G01X115179Y972869D02*
X119506Y966689D01*
G01X116170Y973895D02*
X120831Y967238D01*
G01X114290Y963314D02*
X112058Y964876D01*
G01X114880Y960029D02*
X113284Y962308D01*
G01X116205Y960578D02*
X114290Y963314D01*
G01X117006Y947974D02*
X114880Y960029D01*
G01X117940Y942676D02*
X117601Y944596D01*
G01X118874Y937378D02*
X118535Y939298D01*
G01X121699Y921360D02*
X119470Y934000D01*
G01X114290Y963314D02*
X112058Y964876D01*
G01X116205Y960578D02*
X114290Y963314D01*
G01X114880Y960029D02*
X113284Y962308D01*
G01X117006Y947974D02*
X114880Y960029D01*
G01X117940Y942676D02*
X117601Y944596D01*
G01X118874Y937378D02*
X118535Y939298D01*
G01X121699Y921360D02*
X119470Y934000D01*
G01X113182Y1082367D02*
X125415Y1013000D01*
G01X111857Y1081818D02*
X124090Y1012451D01*
G01X111857Y1081818D02*
X124090Y1012451D01*
G01X113182Y1082367D02*
X125415Y1013000D01*
G01X118208Y1010166D02*
X128273Y995793D01*
G01X118208Y1010166D02*
X128273Y995793D01*
G01X126482Y1033538D02*
X117187Y1086237D01*
G01X125157Y1032989D02*
X115862Y1085688D01*
G01X128937Y1030036D02*
X126482Y1033538D01*
G01X127931Y1029030D02*
X125157Y1032989D01*
G01X130771Y1028751D02*
X128937Y1030036D01*
G01X130222Y1027426D02*
X127931Y1029030D01*
G01X133777Y1028221D02*
X130771Y1028751D01*
G01X133654Y1026821D02*
X130222Y1027426D01*
G01X138196Y1028221D02*
X133777D01*
G01X138194Y1026821D02*
X133654D01*
G01X125157Y1032989D02*
X115862Y1085688D01*
G01X126482Y1033538D02*
X117187Y1086237D01*
G01X127931Y1029030D02*
X125157Y1032989D01*
G01X128937Y1030036D02*
X126482Y1033538D01*
G01X130222Y1027426D02*
X127931Y1029030D01*
G01X130771Y1028751D02*
X128937Y1030036D01*
G01X133654Y1026821D02*
X130222Y1027426D01*
G01X133777Y1028221D02*
X130771Y1028751D01*
G01X138194Y1026821D02*
X133654D01*
G01X138196Y1028221D02*
X133777D01*
G01X134163Y1116410D02*
X124202Y1118166D01*
G01X134040Y1115010D02*
X123653Y1116841D01*
G01X138196Y1116410D02*
X134163D01*
G01X138194Y1115010D02*
X134040D01*
G01D02*
X123653Y1116841D01*
G01X134163Y1116410D02*
X124202Y1118166D01*
G01X138194Y1115010D02*
X134040D01*
G01X138196Y1116410D02*
X134163D01*
G01X125665Y1098943D02*
X115248Y1106237D01*
G01X125116Y1097618D02*
X114242Y1105231D01*
G01X133777Y1097512D02*
X125665Y1098943D01*
G01X133654Y1096112D02*
X125116Y1097618D01*
G01X138196Y1097512D02*
X133777D01*
G01X138194Y1096112D02*
X133654D01*
G01X125116Y1097618D02*
X114242Y1105231D01*
G01X125665Y1098943D02*
X115248Y1106237D01*
G01X133654Y1096112D02*
X125116Y1097618D01*
G01X133777Y1097512D02*
X125665Y1098943D01*
G01X138194Y1096112D02*
X133654D01*
G01X138196Y1097512D02*
X133777D01*
G01X130584Y1079566D02*
X125273Y1083286D01*
G01X130774Y1077722D02*
X124267Y1082280D01*
G01X130924Y1079328D02*
X130584Y1079566D01*
G01X130774Y1077722D02*
X124267Y1082280D01*
G01X131324Y1079047D02*
X130924Y1079328D01*
G01X130774Y1077722D02*
X124267Y1082280D01*
G01X133777Y1078614D02*
X131324Y1079047D01*
G01X133654Y1077214D02*
X130775Y1077722D01*
G01X138195Y1078614D02*
X133777D01*
G01X138195Y1077214D02*
X133654D01*
G01X130774Y1077722D02*
X124267Y1082280D01*
G01X130584Y1079566D02*
X125273Y1083286D01*
G01X130924Y1079328D02*
X130584Y1079566D01*
G01X131324Y1079047D02*
X130924Y1079328D01*
G01X133654Y1077214D02*
X130775Y1077722D01*
G01X133777Y1078614D02*
X131324Y1079047D01*
G01X138195Y1077214D02*
X133654D01*
G01X138195Y1078614D02*
X133777D01*
G01X182313Y1203271D02*
X267060Y1143932D01*
G01X181764Y1201946D02*
X266511Y1142607D01*
G01X153007Y1208440D02*
X182313Y1203271D01*
G01X153007Y1207018D02*
X181764Y1201946D01*
G01D02*
X266511Y1142607D01*
G01X182313Y1203271D02*
X267060Y1143932D01*
G01X153007Y1207018D02*
X181764Y1201946D01*
G01X153007Y1208440D02*
X182313Y1203271D01*
G01X180550Y1199945D02*
X153956Y1204635D01*
G01X180001Y1198620D02*
X153956Y1203213D01*
G01X265948Y1140155D02*
X180550Y1199945D01*
G01X265399Y1138830D02*
X180001Y1198620D01*
G01D02*
X153956Y1203213D01*
G01X180550Y1199945D02*
X153956Y1204635D01*
G01X265399Y1138830D02*
X180001Y1198620D01*
G01X265948Y1140155D02*
X180550Y1199945D01*
G01X179164Y1196549D02*
X153975Y1200992D01*
G01X178615Y1195224D02*
X153975Y1199570D01*
G01X265010Y1136439D02*
X179164Y1196549D01*
G01X264461Y1135114D02*
X178615Y1195224D01*
G01D02*
X153975Y1199570D01*
G01X179164Y1196549D02*
X153975Y1200992D01*
G01X264461Y1135114D02*
X178615Y1195224D01*
G01X265010Y1136439D02*
X179164Y1196549D01*
G01X177694Y1193077D02*
X263376Y1133079D01*
G01X262827Y1131754D02*
X177145Y1191752D01*
G01X153929Y1197268D02*
X177694Y1193077D01*
G01X177145Y1191752D02*
X153929Y1195846D01*
G01X177145Y1191752D02*
X153929Y1195846D01*
G01Y1197268D02*
X177694Y1193077D01*
G01X262827Y1131754D02*
X177145Y1191752D01*
G01X177694Y1193077D02*
X263376Y1133079D01*
G01X117182Y1283318D02*
X115549Y1282175D01*
G01X116176Y1284324D02*
X115002Y1283502D01*
G01X124675Y1294024D02*
X117182Y1283318D01*
G01X120265Y1290165D02*
X116176Y1284324D01*
G01D02*
X115002Y1283502D01*
G01X117182Y1283318D02*
X115549Y1282175D01*
G01X120265Y1290165D02*
X116176Y1284324D01*
G01X124675Y1294024D02*
X117182Y1283318D01*
G01X124675Y1294024D02*
X117182Y1283318D01*
G01X123350Y1294573D02*
X122232Y1292975D01*
G01X127659Y1310947D02*
X124675Y1294024D01*
G01X124368Y1300350D02*
X123350Y1294573D01*
G01X125303Y1305649D02*
X124964Y1303728D01*
G01X126237Y1310947D02*
X125898Y1309027D01*
G01X122234Y1341726D02*
X127659Y1310947D01*
G01X120812Y1341726D02*
X126237Y1310947D01*
G01X127209Y1369942D02*
X122234Y1341726D01*
G01X125787Y1369942D02*
X120812Y1341726D01*
G01X123350Y1294573D02*
X122232Y1292975D01*
G01X124368Y1300350D02*
X123350Y1294573D01*
G01X127659Y1310947D02*
X124675Y1294024D01*
G01X125303Y1305649D02*
X124964Y1303728D01*
G01X127659Y1310947D02*
X124675Y1294024D01*
G01X126237Y1310947D02*
X125898Y1309027D01*
G01X127659Y1310947D02*
X124675Y1294024D01*
G01X120812Y1341726D02*
X126237Y1310947D01*
G01X122234Y1341726D02*
X127659Y1310947D01*
G01X125787Y1369942D02*
X120812Y1341726D01*
G01X127209Y1369942D02*
X122234Y1341726D01*
G01X115515Y1299799D02*
X113663Y1300126D01*
G01X113786Y1301526D02*
X115515Y1301221D01*
G01X118753Y1300370D02*
X115515Y1299799D01*
G01Y1301221D02*
X118204Y1301695D01*
G01X120197Y1301380D02*
X118753Y1300370D01*
G01X118204Y1301695D02*
X119191Y1302386D01*
G01X121046Y1302594D02*
X120197Y1301380D01*
G01X119191Y1302386D02*
X119721Y1303143D01*
G01X123203Y1314825D02*
X121046Y1302594D01*
G01X121442Y1312905D02*
X121781Y1314825D01*
G01X119721Y1303143D02*
X120847Y1309527D01*
G01X118321Y1342508D02*
X123203Y1314825D01*
G01X119912Y1325421D02*
X116899Y1342508D01*
G01X120847Y1320123D02*
X120508Y1322044D01*
G01X121781Y1314825D02*
X121442Y1316745D01*
G01X123147Y1369880D02*
X118321Y1342508D01*
G01X116899D02*
X121725Y1369880D01*
G01X116899Y1342508D02*
X121725Y1369880D01*
G01X123147D02*
X118321Y1342508D01*
G01X119912Y1325421D02*
X116899Y1342508D01*
G01X118321D02*
X123203Y1314825D01*
G01X120847Y1320123D02*
X120508Y1322044D01*
G01X118321Y1342508D02*
X123203Y1314825D01*
G01X121781D02*
X121442Y1316745D01*
G01X118321Y1342508D02*
X123203Y1314825D01*
G01X121442Y1312905D02*
X121781Y1314825D01*
G01X123203D02*
X121046Y1302594D01*
G01X119721Y1303143D02*
X120847Y1309527D01*
G01X123203Y1314825D02*
X121046Y1302594D01*
G01X119191Y1302386D02*
X119721Y1303143D01*
G01X121046Y1302594D02*
X120197Y1301380D01*
G01X118204Y1301695D02*
X119191Y1302386D01*
G01X120197Y1301380D02*
X118753Y1300370D01*
G01X115515Y1301221D02*
X118204Y1301695D01*
G01X118753Y1300370D02*
X115515Y1299799D01*
G01X113786Y1301526D02*
X115515Y1301221D01*
G01Y1299799D02*
X113663Y1300126D01*
G01X111596Y1341342D02*
X118015Y1377734D01*
G01X112412Y1354033D02*
X112751Y1355953D01*
G01X114519Y1324762D02*
X111596Y1341342D01*
G01X113097Y1324762D02*
X112758Y1326682D01*
G01X114057Y1322140D02*
X114519Y1324762D01*
G01X112731Y1322689D02*
X113097Y1324762D01*
G01X112985Y1320608D02*
X114057Y1322140D01*
G01X111979Y1321614D02*
X112731Y1322689D01*
G01X111596Y1341342D02*
X118015Y1377734D01*
G01X112412Y1354033D02*
X112751Y1355953D01*
G01X111596Y1341342D02*
X118015Y1377734D01*
G01X111596Y1341342D02*
X118015Y1377734D01*
G01X111596Y1341342D02*
X118015Y1377734D01*
G01X114519Y1324762D02*
X111596Y1341342D01*
G01X113097Y1324762D02*
X112758Y1326682D01*
G01X114519Y1324762D02*
X111596Y1341342D01*
G01X112731Y1322689D02*
X113097Y1324762D01*
G01X114057Y1322140D02*
X114519Y1324762D01*
G01X111979Y1321614D02*
X112731Y1322689D01*
G01X112985Y1320608D02*
X114057Y1322140D01*
G01X124807Y1383543D02*
X127209Y1369942D01*
G01X123482Y1382995D02*
X125787Y1369942D01*
G01X122037Y1387506D02*
X124808Y1383544D01*
G01X121031Y1386501D02*
X123482Y1382995D01*
G01D02*
X125787Y1369942D01*
G01X124807Y1383543D02*
X127209Y1369942D01*
G01X121031Y1386501D02*
X123482Y1382995D01*
G01X122037Y1387506D02*
X124808Y1383544D01*
G01X121106Y1381466D02*
X123147Y1369880D01*
G01X121725D02*
X119781Y1380917D01*
G01X118827Y1384721D02*
X121106Y1381466D01*
G01X119781Y1380917D02*
X117823Y1383713D01*
G01X119781Y1380917D02*
X117823Y1383713D01*
G01X118827Y1384721D02*
X121106Y1381466D01*
G01X121725Y1369880D02*
X119781Y1380917D01*
G01X121106Y1381466D02*
X123147Y1369880D01*
G01X117787Y1379025D02*
X115526Y1382249D01*
G01X116462Y1378475D02*
X114521Y1381243D01*
G01X118015Y1377734D02*
X117787Y1379025D01*
G01X116593Y1377734D02*
X116462Y1378475D01*
G01X113347Y1359331D02*
X116593Y1377734D01*
G01X116462Y1378475D02*
X114521Y1381243D01*
G01X117787Y1379025D02*
X115526Y1382249D01*
G01X116593Y1377734D02*
X116462Y1378475D01*
G01X118015Y1377734D02*
X117787Y1379025D01*
G01X113347Y1359331D02*
X116593Y1377734D01*
G01X113298Y1374770D02*
X112862Y1377244D01*
G01X111876Y1374770D02*
X111537Y1376695D01*
G01X112877Y1372377D02*
X113298Y1374770D01*
G01X111551Y1372926D02*
X111876Y1374770D01*
G01X111875Y1370945D02*
X112874Y1372375D01*
G01X111876Y1374770D02*
X111537Y1376695D01*
G01X113298Y1374770D02*
X112862Y1377244D01*
G01X111551Y1372926D02*
X111876Y1374770D01*
G01X112877Y1372377D02*
X113298Y1374770D01*
G01X111875Y1370945D02*
X112874Y1372375D01*
G01X133654Y1501624D02*
X138194D01*
G01X123739Y1501298D02*
X133530Y1503024D01*
G01X123739Y1499876D02*
X133654Y1501624D01*
G01D02*
X138194D01*
G01X123739Y1499876D02*
X133654Y1501624D01*
G01X123739Y1501298D02*
X133530Y1503024D01*
G01X133652Y1484127D02*
X121436Y1486302D01*
G01X133406Y1482748D02*
X120886Y1484977D01*
G01X133530Y1482726D02*
X133409Y1482747D01*
G01X133657Y1484126D02*
X133652Y1484127D01*
G01X133406Y1482748D02*
X120886Y1484977D01*
G01X138195Y1484126D02*
X133657D01*
G01X133530Y1482726D02*
X133409Y1482747D01*
G01X138195Y1482726D02*
X133530D01*
G01X133406Y1482748D02*
X120886Y1484977D01*
G01X133652Y1484127D02*
X121436Y1486302D01*
G01X133657Y1484126D02*
X133652Y1484127D01*
G01X133530Y1482726D02*
X133409Y1482747D01*
G01X133652Y1484127D02*
X121436Y1486302D01*
G01X138195Y1484126D02*
X133657D01*
G01X138195Y1482726D02*
X133530D01*
G01X138195Y1484126D02*
X133657D01*
G01X138196Y1433733D02*
X133408D01*
G01X133531Y1432333D02*
X138194D01*
G01X133531D02*
X138194D01*
G01X138196Y1433733D02*
X133408D01*
G01X133917Y1521922D02*
X138196D01*
G01X134040Y1520522D02*
X138194D01*
G01X134040D02*
X138194D01*
G01X133917Y1521922D02*
X138196D01*
G01X133530Y1503024D02*
X138196D01*
G01X133530D02*
X138196D01*
G01X160900Y1647152D02*
X143368Y1672189D01*
G01X159575Y1646603D02*
X158456Y1648200D01*
G01X163034Y1635048D02*
X160900Y1647152D01*
G01X161612Y1635048D02*
X159575Y1646603D01*
G01X162448Y1631726D02*
X163034Y1635048D01*
G01X161123Y1632275D02*
X161612Y1635048D01*
G01X159680Y1627773D02*
X162448Y1631726D01*
G01X158674Y1628779D02*
X161123Y1632275D01*
G01X151624Y1622132D02*
X159680Y1627773D01*
G01X151075Y1623457D02*
X158673Y1628777D01*
G01X160900Y1647152D02*
X143368Y1672189D01*
G01X160900Y1647152D02*
X143368Y1672189D01*
G01X160900Y1647152D02*
X143368Y1672189D01*
G01X160900Y1647152D02*
X143368Y1672189D01*
G01X159575Y1646603D02*
X158456Y1648200D01*
G01X160900Y1647152D02*
X143368Y1672189D01*
G01X161612Y1635048D02*
X159575Y1646603D01*
G01X163034Y1635048D02*
X160900Y1647152D01*
G01X161123Y1632275D02*
X161612Y1635048D01*
G01X162448Y1631726D02*
X163034Y1635048D01*
G01X158674Y1628779D02*
X161123Y1632275D01*
G01X159680Y1627773D02*
X162448Y1631726D01*
G01X151075Y1623457D02*
X158673Y1628777D01*
G01X151624Y1622132D02*
X159680Y1627773D01*
G01X170274Y1634497D02*
X167213Y1651854D01*
G01X165888Y1651304D02*
X168852Y1634497D01*
G01X169438Y1629755D02*
X170274Y1634497D01*
G01X168852D02*
X168113Y1630304D01*
G01X165447Y1624053D02*
X169438Y1629755D01*
G01X168113Y1630304D02*
X164441Y1625059D01*
G01X159495Y1619886D02*
X165447Y1624053D01*
G01X164441Y1625059D02*
X158945Y1621211D01*
G01X164441Y1625059D02*
X158945Y1621211D01*
G01X159495Y1619886D02*
X165447Y1624053D01*
G01X168113Y1630304D02*
X164441Y1625059D01*
G01X165447Y1624053D02*
X169438Y1629755D01*
G01X168852Y1634497D02*
X168113Y1630304D01*
G01X169438Y1629755D02*
X170274Y1634497D01*
G01X165888Y1651304D02*
X168852Y1634497D01*
G01X170274D02*
X167213Y1651854D01*
G01X167006Y1619994D02*
X162369Y1616748D01*
G01X161819Y1618073D02*
X166000Y1621000D01*
G01X173303Y1628989D02*
X167006Y1619994D01*
G01X166000Y1621000D02*
X171978Y1629538D01*
G01X174127Y1633662D02*
X173303Y1628989D01*
G01X171978Y1629538D02*
X172705Y1633662D01*
G01X170601Y1653657D02*
X174127Y1633662D01*
G01X172705D02*
X169276Y1653108D01*
G01X172705Y1633662D02*
X169276Y1653108D01*
G01X170601Y1653657D02*
X174127Y1633662D01*
G01X171978Y1629538D02*
X172705Y1633662D01*
G01X174127D02*
X173303Y1628989D01*
G01X166000Y1621000D02*
X171978Y1629538D01*
G01X173303Y1628989D02*
X167006Y1619994D01*
G01X161819Y1618073D02*
X166000Y1621000D01*
G01X167006Y1619994D02*
X162369Y1616748D01*
G01X169455Y1617209D02*
X163949Y1613354D01*
G01X163399Y1614679D02*
X168449Y1618215D01*
G01X176735Y1627609D02*
X169455Y1617209D01*
G01X168449Y1618215D02*
X175410Y1628158D01*
G01X177789Y1633582D02*
X176735Y1627609D01*
G01X175410Y1628158D02*
X176367Y1633582D01*
G01X172686Y1662525D02*
X177789Y1633582D01*
G01X176367D02*
X171307Y1662281D01*
G01X176367Y1633582D02*
X171307Y1662281D01*
G01X172686Y1662525D02*
X177789Y1633582D01*
G01X175410Y1628158D02*
X176367Y1633582D01*
G01X177789D02*
X176735Y1627609D01*
G01X168449Y1618215D02*
X175410Y1628158D01*
G01X176735Y1627609D02*
X169455Y1617209D01*
G01X163399Y1614679D02*
X168449Y1618215D01*
G01X169455Y1617209D02*
X163949Y1613354D01*
G01X177790Y1611506D02*
X772759Y1506547D01*
G01X177547Y1610126D02*
X772516Y1505167D01*
G01X176436Y1611506D02*
G02X177790I677J-3841D01*
G01X176679Y1610126D02*
G02X177547I434J-2462D01*
G01D02*
X772516Y1505167D01*
G01X177790Y1611506D02*
X772759Y1506547D01*
G01X176679Y1610126D02*
G02X177547I434J-2462D01*
G01X176436Y1611506D02*
G02X177790I677J-3841D01*
G01X177620Y1606351D02*
X815998Y1493773D01*
G01X177863Y1607731D02*
X773695Y1502657D01*
G01X177620Y1606351D02*
X815998Y1493773D01*
G01X176509Y1607731D02*
G02X177863I677J-3841D01*
G01X176752Y1606351D02*
G02X177620I434J-2462D01*
G01D02*
X815998Y1493773D01*
G01X177863Y1607731D02*
X773695Y1502657D01*
G01X176752Y1606351D02*
G02X177620I434J-2462D01*
G01X176509Y1607731D02*
G02X177863I677J-3841D01*
G01X178559Y1603932D02*
X857952Y1484141D01*
G01X178315Y1602553D02*
X857707Y1482762D01*
G01X177204Y1603932D02*
G02X178559I677J-3841D01*
G01X177447Y1602553D02*
G02X178315I434J-2462D01*
G01D02*
X857707Y1482762D01*
G01X178559Y1603932D02*
X857952Y1484141D01*
G01X177447Y1602553D02*
G02X178315I434J-2462D01*
G01X177204Y1603932D02*
G02X178559I677J-3841D01*
G01X178111Y1600159D02*
G03X176757I-677J-3841D01*
G01X177868Y1598779D02*
G03X177000I-434J-2462D01*
G01X773637Y1495159D02*
X178111Y1600159D01*
G01X773394Y1493780D02*
X177868Y1598779D01*
G01D02*
G03X177000I-434J-2462D01*
G01X178111Y1600159D02*
G03X176757I-677J-3841D01*
G01X773394Y1493780D02*
X177868Y1598779D01*
G01X773637Y1495159D02*
X178111Y1600159D01*
G01X124613Y1685322D02*
G03X123661Y1685718I-1376J-1967D01*
G01X123810Y1684175D02*
G03X123413Y1684339I-571J-820D01*
G01X143368Y1672189D02*
X124613Y1685322D01*
G01X125407Y1683056D02*
X123810Y1684175D01*
G01X128217Y1681089D02*
X127186Y1680907D01*
G01X129814Y1679970D02*
X128217Y1681089D01*
G01X132624Y1678003D02*
X131593Y1677821D01*
G01X134221Y1676884D02*
X132624Y1678003D01*
G01X137031Y1674917D02*
X136000Y1674735D01*
G01X142362Y1671183D02*
X137031Y1674917D01*
G01X143481Y1669586D02*
X142362Y1671183D01*
G01X146567Y1665179D02*
X145448Y1666776D01*
G01X149653Y1660772D02*
X148534Y1662369D01*
G01X156489Y1651010D02*
X151620Y1657962D01*
G01X123810Y1684175D02*
G03X123413Y1684339I-571J-820D01*
G01X124613Y1685322D02*
G03X123661Y1685718I-1376J-1967D01*
G01X125407Y1683056D02*
X123810Y1684175D01*
G01X143368Y1672189D02*
X124613Y1685322D01*
G01X128217Y1681089D02*
X127186Y1680907D01*
G01X143368Y1672189D02*
X124613Y1685322D01*
G01X129814Y1679970D02*
X128217Y1681089D01*
G01X143368Y1672189D02*
X124613Y1685322D01*
G01X132624Y1678003D02*
X131593Y1677821D01*
G01X143368Y1672189D02*
X124613Y1685322D01*
G01X134221Y1676884D02*
X132624Y1678003D01*
G01X143368Y1672189D02*
X124613Y1685322D01*
G01X137031Y1674917D02*
X136000Y1674735D01*
G01X143368Y1672189D02*
X124613Y1685322D01*
G01X142362Y1671183D02*
X137031Y1674917D01*
G01X143368Y1672189D02*
X124613Y1685322D01*
G01X143481Y1669586D02*
X142362Y1671183D01*
G01X146567Y1665179D02*
X145448Y1666776D01*
G01X149653Y1660772D02*
X148534Y1662369D01*
G01X156489Y1651010D02*
X151620Y1657962D01*
G01X144512Y1684026D02*
X112266Y1706604D01*
G01X137828Y1686996D02*
X143709Y1682879D01*
G01X136798Y1686815D02*
X137828Y1686996D01*
G01X133421Y1690082D02*
X135018Y1688964D01*
G01X132391Y1689901D02*
X133421Y1690082D01*
G01X145101Y1683437D02*
G03X144512Y1684026I-1966J-1377D01*
G01X143709Y1682879D02*
G02X143954Y1682633I-575J-818D01*
G01X167213Y1651854D02*
X145101Y1683437D01*
G01X163295Y1655009D02*
X165888Y1651305D01*
G01X160209Y1659416D02*
X161327Y1657819D01*
G01X157124Y1663823D02*
X158242Y1662226D01*
G01X150563Y1673194D02*
X155156Y1666633D01*
G01X147477Y1677601D02*
X148596Y1676004D01*
G01X143954Y1682633D02*
X145510Y1680411D01*
G01X163295Y1655009D02*
X165888Y1651305D01*
G01X167213Y1651854D02*
X145101Y1683437D01*
G01X160209Y1659416D02*
X161327Y1657819D01*
G01X167213Y1651854D02*
X145101Y1683437D01*
G01X157124Y1663823D02*
X158242Y1662226D01*
G01X167213Y1651854D02*
X145101Y1683437D01*
G01X150563Y1673194D02*
X155156Y1666633D01*
G01X167213Y1651854D02*
X145101Y1683437D01*
G01X147477Y1677601D02*
X148596Y1676004D01*
G01X167213Y1651854D02*
X145101Y1683437D01*
G01X143954Y1682633D02*
X145510Y1680411D01*
G01X167213Y1651854D02*
X145101Y1683437D01*
G01X143709Y1682879D02*
G02X143954Y1682633I-575J-818D01*
G01X145101Y1683437D02*
G03X144512Y1684026I-1966J-1377D01*
G01X137828Y1686996D02*
X143709Y1682879D01*
G01X144512Y1684026D02*
X112266Y1706604D01*
G01X136798Y1686815D02*
X137828Y1686996D01*
G01X144512Y1684026D02*
X112266Y1706604D01*
G01X133421Y1690082D02*
X135018Y1688964D01*
G01X144512Y1684026D02*
X112266Y1706604D01*
G01X132391Y1689901D02*
X133421Y1690082D01*
G01X144512Y1684026D02*
X112266Y1706604D01*
G01X144512Y1684026D02*
X112266Y1706604D01*
G01X128743Y1713431D02*
X170601Y1653657D01*
G01X128856Y1710828D02*
X127737Y1712425D01*
G01X131942Y1706421D02*
X130823Y1708018D01*
G01X135028Y1702014D02*
X133909Y1703611D01*
G01X142731Y1691013D02*
X136995Y1699204D01*
G01X169276Y1653108D02*
X144699Y1688204D01*
G01X116445Y1720332D02*
X114848Y1721450D01*
G01X119255Y1718364D02*
X118224Y1718183D01*
G01X120852Y1717246D02*
X119255Y1718364D01*
G01X123662Y1715278D02*
X122631Y1715097D01*
G01X127737Y1712425D02*
X123662Y1715278D01*
G01X116445Y1720332D02*
X114848Y1721450D01*
G01X119255Y1718364D02*
X118224Y1718183D01*
G01X120852Y1717246D02*
X119255Y1718364D01*
G01X123662Y1715278D02*
X122631Y1715097D01*
G01X127737Y1712425D02*
X123662Y1715278D01*
G01X128856Y1710828D02*
X127737Y1712425D01*
G01X128743Y1713431D02*
X170601Y1653657D01*
G01X131942Y1706421D02*
X130823Y1708018D01*
G01X128743Y1713431D02*
X170601Y1653657D01*
G01X135028Y1702014D02*
X133909Y1703611D01*
G01X128743Y1713431D02*
X170601Y1653657D01*
G01X142731Y1691013D02*
X136995Y1699204D01*
G01X128743Y1713431D02*
X170601Y1653657D01*
G01X169276Y1653108D02*
X144699Y1688204D01*
G01X128743Y1713431D02*
X170601Y1653657D01*
G01X172289Y1663484D02*
G02X172686Y1662524I-1967J-1375D01*
G01X171306Y1662281D02*
G03X171142Y1662681I-985J-170D01*
G01X123073Y1733771D02*
X172290Y1663485D01*
G01X140973Y1705766D02*
X131006Y1720001D01*
G01X171142Y1662681D02*
X142941Y1702957D01*
G01X123073Y1733771D02*
X172290Y1663485D01*
G01X123073Y1733771D02*
X172290Y1663485D01*
G01X123073Y1733771D02*
X172290Y1663485D01*
G01X140973Y1705766D02*
X131006Y1720001D01*
G01X123073Y1733771D02*
X172290Y1663485D01*
G01X171142Y1662681D02*
X142941Y1702957D01*
G01X123073Y1733771D02*
X172290Y1663485D01*
G01X171306Y1662281D02*
G03X171142Y1662681I-985J-170D01*
G01X172289Y1663484D02*
G02X172686Y1662524I-1967J-1375D01*
G01X145368Y1759405D02*
G02X144754Y1760019I1434J2048D01*
G01X144561Y1758260D02*
G02X143604Y1759218I2239J3194D01*
G01X159047Y1749825D02*
X145368Y1759405D01*
G01X158498Y1748500D02*
X144561Y1758260D01*
G01X165003Y1748775D02*
X159047Y1749825D01*
G01X165000Y1747353D02*
X158498Y1748500D01*
G01X742852Y1850646D02*
X165003Y1748775D01*
G01X743401Y1849321D02*
X165003Y1747353D01*
G01X144561Y1758260D02*
G02X143604Y1759218I2239J3194D01*
G01X145368Y1759405D02*
G02X144754Y1760019I1434J2048D01*
G01X158498Y1748500D02*
X144561Y1758260D01*
G01X159047Y1749825D02*
X145368Y1759405D01*
G01X165000Y1747353D02*
X158498Y1748500D01*
G01X165003Y1748775D02*
X159047Y1749825D01*
G01X743401Y1849321D02*
X165003Y1747353D01*
G01X742852Y1850646D02*
X165003Y1748775D01*
G01X164932Y1744894D02*
X768730Y1851321D01*
G01X164932Y1743472D02*
X769273Y1849995D01*
G01X157772Y1746157D02*
X164932Y1744894D01*
G01X157223Y1744832D02*
X164932Y1743472D01*
G01X142793Y1756647D02*
X157772Y1746157D01*
G01X141990Y1755499D02*
X157223Y1744832D01*
G01X141986Y1755502D02*
X141990Y1755499D01*
G01X142179Y1757260D02*
G03X142793Y1756646I2048J1434D01*
G01X141029Y1756459D02*
G03X141986Y1755502I3194J2237D01*
G01X118690Y1790792D02*
X142177Y1757263D01*
G01X117543Y1789989D02*
X141029Y1756459D01*
G01X118099Y1791384D02*
G02X118688Y1790795I-1377J-1966D01*
G01X117298Y1790234D02*
G02X117543Y1789989I-574J-819D01*
G01X117295Y1790236D02*
X117298Y1790234D01*
G01X164932Y1743472D02*
X769273Y1849995D01*
G01X164932Y1744894D02*
X768730Y1851321D01*
G01X157223Y1744832D02*
X164932Y1743472D01*
G01X157772Y1746157D02*
X164932Y1744894D01*
G01X141990Y1755499D02*
X157223Y1744832D01*
G01X142793Y1756647D02*
X157772Y1746157D01*
G01X141986Y1755502D02*
X141990Y1755499D01*
G01X142793Y1756647D02*
X157772Y1746157D01*
G01X141029Y1756459D02*
G03X141986Y1755502I3194J2237D01*
G01X142179Y1757260D02*
G03X142793Y1756646I2048J1434D01*
G01X117543Y1789989D02*
X141029Y1756459D01*
G01X118690Y1790792D02*
X142177Y1757263D01*
G01X117298Y1790234D02*
G02X117543Y1789989I-574J-819D01*
G01X118099Y1791384D02*
G02X118688Y1790795I-1377J-1966D01*
G01X117295Y1790236D02*
X117298Y1790234D01*
G01X164841Y1740919D02*
X792127Y1851586D01*
G01X164841Y1739496D02*
X792676Y1850261D01*
G01X156245Y1742436D02*
X164840Y1740919D01*
G01X155697Y1741110D02*
X164841Y1739497D01*
G01X140361Y1753558D02*
X156245Y1742436D01*
G01X139559Y1752409D02*
X155697Y1741110D01*
G01X139747Y1754172D02*
G03X140361Y1753558I2048J1434D01*
G01X138601Y1753366D02*
G03X139559Y1752409I3193J2239D01*
G01X116471Y1787407D02*
X139746Y1754172D01*
G01X115465Y1786401D02*
X138599Y1753369D01*
G01X164841Y1739496D02*
X792676Y1850261D01*
G01X164841Y1740919D02*
X792127Y1851586D01*
G01X155697Y1741110D02*
X164841Y1739497D01*
G01X156245Y1742436D02*
X164840Y1740919D01*
G01X139559Y1752409D02*
X155697Y1741110D01*
G01X140361Y1753558D02*
X156245Y1742436D01*
G01X138601Y1753366D02*
G03X139559Y1752409I3193J2239D01*
G01X139747Y1754172D02*
G03X140361Y1753558I2048J1434D01*
G01X115465Y1786401D02*
X138599Y1753369D01*
G01X116471Y1787407D02*
X139746Y1754172D01*
G01X114848Y1721450D02*
X113817Y1721268D01*
G01X114848Y1721450D02*
X113817Y1721268D01*
G01X122866Y1731625D02*
X121748Y1733222D01*
G01X125952Y1727218D02*
X124834Y1728815D01*
G01X129038Y1722811D02*
X127920Y1724408D01*
G01X116325Y1772049D02*
X123073Y1733771D01*
G01X115338Y1769580D02*
X114999Y1771500D01*
G01X116272Y1764281D02*
X115933Y1766202D01*
G01X117206Y1758983D02*
X116867Y1760903D01*
G01X121748Y1733222D02*
X117801Y1755605D01*
G01X115182Y1773683D02*
X116325Y1772049D01*
G01X114904Y1771636D02*
X114176Y1772677D01*
G01X114999Y1771500D02*
X114904Y1771636D01*
G01X112169Y1775791D02*
X115182Y1773682D01*
G01X114176Y1772677D02*
X111620Y1774466D01*
G01X114176Y1772677D02*
X111620Y1774466D01*
G01X112169Y1775791D02*
X115182Y1773682D01*
G01X114904Y1771636D02*
X114176Y1772677D01*
G01X115182Y1773683D02*
X116325Y1772049D01*
G01X114999Y1771500D02*
X114904Y1771636D01*
G01X115182Y1773683D02*
X116325Y1772049D01*
G01X115338Y1769580D02*
X114999Y1771500D01*
G01X116325Y1772049D02*
X123073Y1733771D01*
G01X116272Y1764281D02*
X115933Y1766202D01*
G01X116325Y1772049D02*
X123073Y1733771D01*
G01X117206Y1758983D02*
X116867Y1760903D01*
G01X116325Y1772049D02*
X123073Y1733771D01*
G01X121748Y1733222D02*
X117801Y1755605D01*
G01X116325Y1772049D02*
X123073Y1733771D01*
G01X122866Y1731625D02*
X121748Y1733222D01*
G01X125952Y1727218D02*
X124834Y1728815D01*
G01X129038Y1722811D02*
X127920Y1724408D01*
G01X115823Y1779524D02*
X115822D01*
G01X136978Y1751750D02*
X116829Y1780530D01*
G01X135830Y1750947D02*
X115823Y1779524D01*
G01X137592Y1751136D02*
G02X136978Y1751750I1434J2048D01*
G01X136789Y1749988D02*
G02X135830Y1750947I2236J3195D01*
G01X156120Y1738166D02*
X137592Y1751136D01*
G01X155571Y1736841D02*
X136789Y1749989D01*
G01X164013Y1736773D02*
X156120Y1738166D01*
G01X164013Y1735351D02*
X155571Y1736841D01*
G01X809209Y1850611D02*
X164013Y1736773D01*
G01X809184Y1849184D02*
X164013Y1735351D01*
G01X115823Y1779524D02*
X115822D01*
G01X135830Y1750947D02*
X115823Y1779524D01*
G01X136978Y1751750D02*
X116829Y1780530D01*
G01X136789Y1749988D02*
G02X135830Y1750947I2236J3195D01*
G01X137592Y1751136D02*
G02X136978Y1751750I1434J2048D01*
G01X155571Y1736841D02*
X136789Y1749989D01*
G01X156120Y1738166D02*
X137592Y1751136D01*
G01X164013Y1735351D02*
X155571Y1736841D01*
G01X164013Y1736773D02*
X156120Y1738166D01*
G01X809184Y1849184D02*
X164013Y1735351D01*
G01X809209Y1850611D02*
X164013Y1736773D01*
G01X138196Y1839245D02*
X133531D01*
G01X138194Y1837845D02*
X133408D01*
G01X138194D02*
X133408D01*
G01X138196Y1839245D02*
X133531D01*
G01X138194Y1926034D02*
X134040D01*
G01X138196Y1927434D02*
X133917D01*
G01X138196D02*
X133917D01*
G01X138194Y1926034D02*
X134040D01*
G01X138194Y1907136D02*
X133654D01*
G01X138196Y1908536D02*
X133531D01*
G01X138196D02*
X133531D01*
G01X138194Y1907136D02*
X133654D01*
G01X133531Y1888238D02*
X112270Y1891986D01*
G01X133654Y1889638D02*
X112273Y1893408D01*
G01X138195Y1888238D02*
X133531D01*
G01X138195Y1889638D02*
X133654D01*
G01D02*
X112273Y1893408D01*
G01X133531Y1888238D02*
X112270Y1891986D01*
G01X138195Y1889638D02*
X133654D01*
G01X138195Y1888238D02*
X133531D01*
G01X229506Y841193D02*
X328861Y771629D01*
G01X228500Y840187D02*
X328312Y770304D01*
G01X228500Y840187D02*
X328312Y770304D01*
G01X229506Y841193D02*
X328861Y771629D01*
G01X223905Y838767D02*
X323773Y768839D01*
G01X222899Y837761D02*
X323224Y767514D01*
G01X222899Y837761D02*
X323224Y767514D01*
G01X223905Y838767D02*
X323773Y768839D01*
G01X221284Y836266D02*
X322770Y765205D01*
G01X220637Y835009D02*
X322221Y763880D01*
G01X220479Y835120D02*
X220637Y835009D01*
G01X220476Y835122D02*
X220479Y835120D01*
G01X220274Y835263D02*
X220476Y835122D01*
G01X220637Y835009D02*
X322221Y763880D01*
G01X221284Y836266D02*
X322770Y765205D01*
G01X220479Y835120D02*
X220637Y835009D01*
G01X221284Y836266D02*
X322770Y765205D01*
G01X220476Y835122D02*
X220479Y835120D01*
G01X221284Y836266D02*
X322770Y765205D01*
G01X220274Y835263D02*
X220476Y835122D01*
G01X221284Y836266D02*
X322770Y765205D01*
G01X321325Y761704D02*
X218531Y833681D01*
G01X320776Y760379D02*
X217525Y832675D01*
G01X320776Y760379D02*
X217525Y832675D01*
G01X321325Y761704D02*
X218531Y833681D01*
G01X328861Y771629D02*
X765405Y694655D01*
G01X328312Y770304D02*
X765405Y693233D01*
G01X328312Y770304D02*
X765405Y693233D01*
G01X328861Y771629D02*
X765405Y694655D01*
G01X323773Y768839D02*
X779815Y688421D01*
G01X323224Y767514D02*
X779815Y686999D01*
G01X323224Y767514D02*
X779815Y686999D01*
G01X323773Y768839D02*
X779815Y688421D01*
G01X322770Y765205D02*
X801830Y680734D01*
G01X322221Y763880D02*
X801306Y679404D01*
G01X322221Y763880D02*
X801306Y679404D01*
G01X322770Y765205D02*
X801830Y680734D01*
G01X770136Y682552D02*
X321325Y761704D01*
G01X769612Y681222D02*
X320776Y760379D01*
G01X769612Y681222D02*
X320776Y760379D01*
G01X770136Y682552D02*
X321325Y761704D01*
G01X266511Y1142607D02*
X642707Y1076275D01*
G01X266511Y1142607D02*
X642707Y1076275D01*
G01X267060Y1143932D02*
X452900Y1111165D01*
G01X266511Y1142607D02*
X642707Y1076275D01*
G01X266511Y1142607D02*
X642707Y1076275D01*
G01X267060Y1143932D02*
X452900Y1111165D01*
G01X684886Y1066304D02*
X265948Y1140155D01*
G01X684886Y1064882D02*
X265399Y1138830D01*
G01X684886Y1064882D02*
X265399Y1138830D01*
G01X684886Y1064882D02*
X265399Y1138830D01*
G01X684886Y1066304D02*
X265948Y1140155D01*
G01X727443Y1054910D02*
X265010Y1136439D01*
G01X727443Y1053488D02*
X264461Y1135114D01*
G01X727443Y1053488D02*
X264461Y1135114D01*
G01X727443Y1054910D02*
X265010Y1136439D01*
G01X263376Y1133079D02*
X857949Y1028221D01*
G01X857826Y1026821D02*
X262827Y1131754D01*
G01X857826Y1026821D02*
X262827Y1131754D01*
G01X263376Y1133079D02*
X857949Y1028221D01*
G01X804620Y315716D02*
X355144Y630453D01*
G01X804071Y314391D02*
X354138Y629447D01*
G01X804071Y314391D02*
X354138Y629447D01*
G01X804620Y315716D02*
X355144Y630453D01*
G01X832066Y291745D02*
X352905Y627264D01*
G01X831517Y290420D02*
X351897Y626259D01*
G01X831517Y290420D02*
X351897Y626259D01*
G01X832066Y291745D02*
X352905Y627264D01*
G01X350170Y624477D02*
X859185Y268065D01*
G01X349165Y623470D02*
X858636Y266740D01*
G01X349165Y623470D02*
X858636Y266740D01*
G01X350170Y624477D02*
X859185Y268065D01*
G01X347960Y621186D02*
X805028Y301139D01*
G01X346954Y620180D02*
X804002Y300148D01*
G01X346954Y620180D02*
X804002Y300148D01*
G01X347960Y621186D02*
X805028Y301139D01*
G01X452900Y1111165D02*
X501919Y1102522D01*
G01X452900Y1111165D02*
X501919Y1102522D01*
G01D02*
X642706Y1077697D01*
G01X501919Y1102522D02*
X642706Y1077697D01*
G01X862000Y1096112D02*
X684898Y1064884D01*
G01X862000Y1096112D02*
X684898Y1064884D01*
G01X862000Y1096112D02*
X684898Y1064884D01*
G01X642706Y1077697D02*
X862263Y1116410D01*
G01X642707Y1076275D02*
X862386Y1115010D01*
G01X642707Y1076275D02*
X862386Y1115010D01*
G01X642706Y1077697D02*
X862263Y1116410D01*
G01X684898Y1066306D02*
X684886Y1066304D01*
G01X861877Y1097512D02*
X684898Y1066306D01*
G01D02*
X684886Y1066304D01*
G01X684898Y1066306D02*
X684886Y1066304D01*
G01X861877Y1097512D02*
X684898Y1066306D01*
G01X765405Y694655D02*
X857524Y710898D01*
G01X765405Y693233D02*
X857647Y709498D01*
G01X765405Y693233D02*
X857647Y709498D01*
G01X765405Y694655D02*
X857524Y710898D01*
G01X861877Y1078614D02*
X727443Y1054910D01*
G01X862000Y1077214D02*
X727443Y1053488D01*
G01X862000Y1077214D02*
X727443Y1053488D01*
G01X861877Y1078614D02*
X727443Y1054910D01*
G01X849366Y1925229D02*
X742852Y1850646D01*
G01X849915Y1923904D02*
X743401Y1849321D01*
G01X849915Y1923904D02*
X743401Y1849321D01*
G01X849366Y1925229D02*
X742852Y1850646D01*
G01X805028Y301139D02*
X857162Y220857D01*
G01X804002Y300148D02*
X856149Y219844D01*
G01X804002Y300148D02*
X856149Y219844D01*
G01X805028Y301139D02*
X857162Y220857D01*
G01X863000Y305386D02*
X804620Y315716D01*
G01X862877Y303986D02*
X804071Y314391D01*
G01X862877Y303986D02*
X804071Y314391D01*
G01X863000Y305386D02*
X804620Y315716D01*
G01X861877Y286488D02*
X832066Y291745D01*
G01X861754Y285088D02*
X831517Y290420D01*
G01X861754Y285088D02*
X831517Y290420D01*
G01X861877Y286488D02*
X832066Y291745D01*
G01X834400Y698046D02*
X862836Y692000D01*
G01X834375Y696619D02*
X862688Y690600D01*
G01X779815Y688421D02*
X834400Y698046D01*
G01X779815Y686999D02*
X834375Y696619D01*
G01D02*
X862688Y690600D01*
G01X834400Y698046D02*
X862836Y692000D01*
G01X779815Y686999D02*
X834375Y696619D01*
G01X779815Y688421D02*
X834400Y698046D01*
G01X837044Y667966D02*
X861208Y673102D01*
G01X837044Y666534D02*
X858374Y671068D01*
G01X813930Y672880D02*
X837044Y667966D01*
G01X813385Y671564D02*
X837044Y666534D01*
G01X801830Y680734D02*
X813930Y672880D01*
G01X801306Y679404D02*
X813385Y671564D01*
G01X837044Y667966D02*
X861208Y673102D01*
G01X837044Y666534D02*
X858374Y671068D01*
G01X837044Y667966D02*
X861208Y673102D01*
G01X813385Y671564D02*
X837044Y666534D01*
G01X813930Y672880D02*
X837044Y667966D01*
G01X801306Y679404D02*
X813385Y671564D01*
G01X801830Y680734D02*
X813930Y672880D01*
G01X862293Y622709D02*
X770136Y682552D01*
G01X861878Y621309D02*
X769612Y681222D01*
G01X861878Y621309D02*
X769612Y681222D01*
G01X862293Y622709D02*
X770136Y682552D01*
G01X817109Y1495153D02*
X861754Y1503024D01*
G01X817352Y1493773D02*
X861877Y1501624D01*
G01X816241Y1495153D02*
G03X817109I434J2462D01*
G01X815998Y1493773D02*
G03X817352I677J3841D01*
G01X773695Y1502656D02*
X816241Y1495153D01*
G01X817352Y1493773D02*
X861877Y1501624D01*
G01X817109Y1495153D02*
X861754Y1503024D01*
G01X815998Y1493773D02*
G03X817352I677J3841D01*
G01X816241Y1495153D02*
G03X817109I434J2462D01*
G01X773695Y1502656D02*
X816241Y1495153D01*
G01X775197Y1494513D02*
G03X773637Y1495159I-2237J-3195D01*
G01X774394Y1493366D02*
G03X773394Y1493780I-1434J-2048D01*
G01X862000Y1433733D02*
X775197Y1494513D01*
G01X861558Y1432333D02*
X774394Y1493366D01*
G01D02*
G03X773394Y1493780I-1434J-2048D01*
G01X775197Y1494513D02*
G03X773637Y1495159I-2237J-3195D01*
G01X861558Y1432333D02*
X774394Y1493366D01*
G01X862000Y1433733D02*
X775197Y1494513D01*
G01X773627Y1506547D02*
X860826Y1521922D01*
G01X773870Y1505167D02*
X860949Y1520522D01*
G01X772759Y1506547D02*
G03X773627I434J2462D01*
G01X772516Y1505167D02*
G03X773870I677J3841D01*
G01D02*
X860949Y1520522D01*
G01X773627Y1506547D02*
X860826Y1521922D01*
G01X772516Y1505167D02*
G03X773870I677J3841D01*
G01X772759Y1506547D02*
G03X773627I434J2462D01*
G01X768730Y1851321D02*
X846573Y1905838D01*
G01X769278Y1849995D02*
X847122Y1904513D01*
G01X769278Y1849995D02*
X847122Y1904513D01*
G01X768730Y1851321D02*
X846573Y1905838D01*
G01X792127Y1851586D02*
X844585Y1888316D01*
G01X792676Y1850261D02*
X845134Y1886991D01*
G01X792676Y1850261D02*
X845134Y1886991D01*
G01X792127Y1851586D02*
X844585Y1888316D01*
G01X862664Y1839245D02*
X809209Y1850611D01*
G01X862516Y1837845D02*
X809184Y1849184D01*
G01X862516Y1837845D02*
X809184Y1849184D01*
G01X862664Y1839245D02*
X809209Y1850611D01*
G01X862799Y217197D02*
X866542D01*
G01X862384Y215797D02*
X866540D01*
G01X859980Y219027D02*
X862799Y217197D01*
G01X856149Y219844D02*
X862384Y215797D01*
G01X857162Y220857D02*
X859980Y219027D01*
G01X856149Y219844D02*
X862384Y215797D01*
G01D02*
X866540D01*
G01X862799Y217197D02*
X866542D01*
G01X856149Y219844D02*
X862384Y215797D01*
G01X859980Y219027D02*
X862799Y217197D01*
G01X857162Y220857D02*
X859980Y219027D01*
G01X866542Y305386D02*
X863000D01*
G01X866540Y303986D02*
X862877D01*
G01X866540D02*
X862877D01*
G01X866542Y305386D02*
X863000D01*
G01X866542Y286488D02*
X861877D01*
G01X866540Y285088D02*
X861754D01*
G01X866540D02*
X861754D01*
G01X866542Y286488D02*
X861877D01*
G01Y267590D02*
X866541D01*
G01X861754Y266190D02*
X866541D01*
G01X859185Y268065D02*
X861877Y267590D01*
G01X858636Y266740D02*
X861754Y266190D01*
G01D02*
X866541D01*
G01X861877Y267590D02*
X866541D01*
G01X858636Y266740D02*
X861754Y266190D01*
G01X859185Y268065D02*
X861877Y267590D01*
G01X866542Y622709D02*
X862293D01*
G01X866540Y621309D02*
X861878D01*
G01X866540D02*
X861878D01*
G01X866542Y622709D02*
X862293D01*
G01X862836Y692000D02*
X866542D01*
G01X862688Y690600D02*
X866540D01*
G01X862688D02*
X866540D01*
G01X862836Y692000D02*
X866542D01*
G01X861208Y673102D02*
X866541D01*
G01X861359Y671702D02*
X866541D01*
G01X858374Y671068D02*
X861359Y671702D01*
G01D02*
X866541D01*
G01X861208Y673102D02*
X866541D01*
G01X858374Y671068D02*
X861359Y671702D01*
G01X857524Y710898D02*
X866542D01*
G01X857647Y709498D02*
X866540D01*
G01X857647D02*
X866540D01*
G01X857524Y710898D02*
X866542D01*
G01X857949Y1028221D02*
X866542D01*
G01X866540Y1026821D02*
X857826D01*
G01X866540D02*
X857826D01*
G01X857949Y1028221D02*
X866542D01*
G01X862263Y1116410D02*
X866542D01*
G01X862386Y1115010D02*
X866540D01*
G01X862386D02*
X866540D01*
G01X862263Y1116410D02*
X866542D01*
G01Y1097512D02*
X861877D01*
G01X866540Y1096112D02*
X862000D01*
G01X866540D02*
X862000D01*
G01X866542Y1097512D02*
X861877D01*
G01X866541Y1078614D02*
X861877D01*
G01X866541Y1077214D02*
X862000D01*
G01X866541D02*
X862000D01*
G01X866541Y1078614D02*
X861877D01*
G01Y1501624D02*
X866540D01*
G01X861877D02*
X866540D01*
G01X858126Y1484126D02*
X866541D01*
G01X858124Y1482726D02*
X866541D01*
G01X857952Y1484141D02*
G03X858126Y1484126I173J985D01*
G01X857707Y1482762D02*
G03X858124Y1482726I414J2364D01*
G01D02*
X866541D01*
G01X858126Y1484126D02*
X866541D01*
G01X857707Y1482762D02*
G03X858124Y1482726I414J2364D01*
G01X857952Y1484141D02*
G03X858126Y1484126I173J985D01*
G01X866542Y1433733D02*
X862000D01*
G01X866540Y1432333D02*
X861558D01*
G01X866540D02*
X861558D01*
G01X866542Y1433733D02*
X862000D01*
G01X860826Y1521922D02*
X866542D01*
G01X860949Y1520522D02*
X866540D01*
G01X860949D02*
X866540D01*
G01X860826Y1521922D02*
X866542D01*
G01X861754Y1503024D02*
X866542D01*
G01X861754D02*
X866542D01*
G01Y1839245D02*
X862664D01*
G01X866540Y1837845D02*
X862516D01*
G01X866540D02*
X862516D01*
G01X866542Y1839245D02*
X862664D01*
G01X861873Y1927434D02*
X849366Y1925229D01*
G01X861996Y1926034D02*
X849915Y1923904D01*
G01X866542Y1927434D02*
X861873D01*
G01X866540Y1926034D02*
X861996D01*
G01D02*
X849915Y1923904D01*
G01X861873Y1927434D02*
X849366Y1925229D01*
G01X866540Y1926034D02*
X861996D01*
G01X866542Y1927434D02*
X861873D01*
G01X861877Y1908536D02*
X866542D01*
G01X862000Y1907136D02*
X866540D01*
G01X846573Y1905838D02*
X861877Y1908536D01*
G01X847122Y1904513D02*
X862000Y1907136D01*
G01D02*
X866540D01*
G01X861877Y1908536D02*
X866542D01*
G01X847122Y1904513D02*
X862000Y1907136D01*
G01X846573Y1905838D02*
X861877Y1908536D01*
G01X851870Y1889600D02*
X866503D01*
G01X851993Y1888200D02*
X866579D01*
G01X844585Y1888316D02*
X851870Y1889600D01*
G01X845134Y1886991D02*
X851993Y1888200D01*
G01D02*
X866579D01*
G01X851870Y1889600D02*
X866503D01*
G01X845134Y1886991D02*
X851993Y1888200D01*
G01X844585Y1888316D02*
X851870Y1889600D01*
M02*
